G04 ================== begin FILE IDENTIFICATION RECORD ==================*
G04 Layout Name:  9127_F0T_Expander_BD_F_v02_0110_1240.brd*
G04 Film Name:    smb*
G04 File Format:  Gerber RS274X*
G04 File Origin:  Cadence Allegro 17.2-S081*
G04 Origin Date:  Wed Jan 11 16:06:13 2023*
G04 *
G04 Layer:  DRAWING FORMAT/TITLE_BLOCK_A*
G04 Layer:  DRAWING FORMAT/TITLE_BLOCK*
G04 Layer:  VIA CLASS/SOLDERMASK_BOTTOM*
G04 Layer:  PIN/SOLDERMASK_BOTTOM*
G04 Layer:  PACKAGE GEOMETRY/SOLDERMASK_BOTTOM*
G04 Layer:  MANUFACTURING/PHOTOPLOT_OUTLINE*
G04 Layer:  DRAWING FORMAT/TITLE_DATA_SMB*
G04 Layer:  BOARD GEOMETRY/SOLDERMASK_BOTTOM*
G04 *
G04 Offset:    (0.00 0.00)*
G04 Mirror:    No*
G04 Mode:      Positive*
G04 Rotation:  0*
G04 FullContactRelief:  No*
G04 UndefLineWidth:     6.00*
G04 ================== end FILE IDENTIFICATION RECORD ====================*
%FSLAX25Y25*MOIN*%
%IR0*IPPOS*OFA0.00000B0.00000*MIA0B0*SFA1.00000B1.00000*%
%ADD45O,.141X.066*%
%ADD30O,.141X.068*%
%ADD11C,.03*%
%ADD89C,.05*%
%ADD79C,.032*%
%ADD21C,.024*%
%ADD80C,.052*%
%ADD72C,.061*%
%ADD50R,.0081X.016*%
%ADD43C,.0322*%
%ADD38C,.034*%
%ADD55R,.016X.0081*%
%ADD84C,.072*%
%ADD31C,.064*%
%ADD91C,.065*%
%ADD66R,.115X.099*%
%ADD98C,.085*%
%ADD44C,.068*%
%ADD42R,.0322X.0322*%
%AMMACRO88*
4,1,8,.0445,-.08,
.0445,.08,
-.0445,.08,
-.0445,.0216,
-.0165,.0216,
-.0165,-.0216,
-.0445,-.0216,
-.0445,-.08,
.0445,-.08,
0.0*
%
%ADD88MACRO88*%
%ADD41C,.0259*%
%ADD78C,.07451*%
%ADD36C,.0395*%
%ADD92R,.065X.065*%
%ADD33C,.0785*%
%ADD90R,.07451X.07451*%
%AMMACRO85*
4,1,8,.0034,.0082,
-.0034,.0082,
-.0082,.0034,
-.0082,-.00341,
-.00341,-.0082,
.0034,-.0082,
.0082,-.0034,
.0082,.0034,
.0034,.0082,
0.0*
%
%ADD85MACRO85*%
%AMMACRO27*
4,1,28,-.00589,.01192,
-.006913,.011842,
-.007907,.011587,
-.008842,.011163,
-.009688,.010584,
-.010422,.009866,
-.011019,.009032,
-.011463,.008107,
-.011739,.007119,
-.01184,.006097,
-.01184,.00603,
-.01184,-.00148,
-.00948,-.00148,
-.00948,-.01191,
.00948,-.01191,
.00948,-.00148,
.01184,-.00148,
.01184,.00603,
.011751,.007052,
.011486,.008044,
.011053,.008974,
.010465,.009815,
.00974,.010541,
.0089,.01113,
.00797,.011564,
.006979,.01183,
.005957,.01192,
.00589,.01192,
-.00589,.01192,
0.0*
%
%ADD27MACRO27*%
%AMMACRO86*
4,1,8,.0082,-.0034,
.0082,.0034,
.0034,.0082,
-.00341,.0082,
-.0082,.00341,
-.0082,-.0034,
-.0034,-.0082,
.0034,-.0082,
.0082,-.0034,
0.0*
%
%ADD86MACRO86*%
%ADD40C,.03968*%
%AMMACRO35*
4,1,28,.01192,.00589,
.011842,.006913,
.011587,.007907,
.011163,.008842,
.010584,.009688,
.009866,.010422,
.009032,.011019,
.008107,.011463,
.007119,.011739,
.006097,.01184,
.00603,.01184,
-.00148,.01184,
-.00148,.00948,
-.01191,.00948,
-.01191,-.00948,
-.00148,-.00948,
-.00148,-.01184,
.00603,-.01184,
.007052,-.011751,
.008044,-.011486,
.008974,-.011053,
.009815,-.010465,
.010541,-.00974,
.01113,-.0089,
.011564,-.00797,
.01183,-.006979,
.01192,-.005957,
.01192,-.00589,
.01192,.00589,
0.0*
%
%ADD35MACRO35*%
%AMMACRO26*
4,1,28,.0059,-.01191,
.006923,-.01183,
.007916,-.011573,
.00885,-.011148,
.009696,-.010567,
.010428,-.009849,
.011024,-.009013,
.011466,-.008088,
.011741,-.007099,
.01184,-.006078,
.01184,-.00602,
.01184,.00149,
.00948,.00149,
.00948,.01192,
-.00948,.01192,
-.00948,.00149,
-.01184,.00149,
-.01184,-.00602,
-.011751,-.007042,
-.011486,-.008033,
-.011053,-.008964,
-.010465,-.009805,
-.00974,-.010531,
-.0089,-.01112,
-.007971,-.011554,
-.00698,-.01182,
-.005958,-.01191,
-.0059,-.01191,
.0059,-.01191,
0.0*
%
%ADD26MACRO26*%
%AMMACRO34*
4,1,28,-.01191,-.0059,
-.01183,-.006923,
-.011573,-.007916,
-.011148,-.00885,
-.010567,-.009696,
-.009849,-.010428,
-.009013,-.011024,
-.008088,-.011466,
-.007099,-.011741,
-.006078,-.01184,
-.00602,-.01184,
.00149,-.01184,
.00149,-.00948,
.01192,-.00948,
.01192,.00948,
.00149,.00948,
.00149,.01184,
-.00602,.01184,
-.007042,.011751,
-.008033,.011486,
-.008964,.011053,
-.009805,.010465,
-.010531,.00974,
-.01112,.0089,
-.011554,.007971,
-.01182,.00698,
-.01191,.005958,
-.01191,.0059,
-.01191,-.0059,
0.0*
%
%ADD34MACRO34*%
%ADD51R,.04X.02*%
%ADD97R,.021X.05*%
%ADD62R,.022X.024*%
%ADD67R,.024X.014*%
%ADD61R,.022X.024*%
%ADD82R,.024X.015*%
%ADD48R,.028X.02*%
%ADD25C,.12*%
%ADD13R,.014X.024*%
%ADD93R,.04X.036*%
%ADD74R,.024X.016*%
%ADD63R,.026X.014*%
%ADD57R,.02X.028*%
%ADD53R,.028X.021*%
%ADD81R,.025X.016*%
%ADD65R,.014X.026*%
%ADD15R,.036X.032*%
%ADD54R,.032X.036*%
%ADD102C,.142*%
%ADD96R,.028X.05*%
%AMMACRO47*
21,1,.016,.0081,0.0,0.0,135.*%
%ADD47MACRO47*%
%ADD46R,.019X.016*%
%ADD32R,.054X.044*%
%ADD10C,.26*%
%ADD60R,.071X.046*%
%ADD24R,.016X.019*%
%ADD23C,.162*%
%ADD16R,.044X.054*%
%ADD99R,.036X.028*%
%ADD75C,.154*%
%ADD17C,.145*%
%ADD12R,.046X.071*%
%ADD101O,.048X.091*%
%ADD68R,.083X.063*%
%ADD56R,.028X.028*%
%ADD52R,.057X.026*%
%ADD95R,.018X.056*%
%ADD94R,.028X.046*%
%ADD76R,.016X.067*%
%ADD70R,.048X.018*%
%AMMACRO58*
21,1,.016,.0081,0.0,0.0,123.215*%
%ADD58MACRO58*%
%ADD49R,.028X.028*%
%ADD37R,.018X.065*%
%ADD14R,.063X.083*%
%ADD100O,.048X.075*%
%ADD77C,.319*%
%ADD71R,.018X.048*%
%ADD69R,.048X.028*%
%AMMACRO73*
4,1,8,-.0445,.08,
-.0445,-.08,
.0445,-.08,
.0445,-.0216,
.0165,-.0216,
.0165,.0216,
.0445,.0216,
.0445,.08,
-.0445,.08,
0.0*
%
%ADD73MACRO73*%
%ADD18R,.058X.048*%
%ADD59R,.048X.058*%
%ADD64R,.128X.128*%
%ADD39C,.198*%
%ADD22C,.398*%
%AMMACRO87*
4,1,8,-.0034,-.0082,
.0034,-.0082,
.0082,-.0034,
.0082,.00341,
.00341,.0082,
-.0034,.0082,
-.0082,.0034,
-.0082,-.0034,
-.0034,-.0082,
0.0*
%
%ADD87MACRO87*%
%AMMACRO83*
4,1,8,-.0082,.0034,
-.0082,-.0034,
-.0034,-.0082,
.00341,-.0082,
.0082,-.00341,
.0082,.0034,
.0034,.0082,
-.0034,.0082,
-.0082,.0034,
0.0*
%
%ADD83MACRO83*%
%AMMACRO29*
4,1,28,-.01192,-.00589,
-.011842,-.006913,
-.011587,-.007907,
-.011163,-.008842,
-.010584,-.009688,
-.009866,-.010422,
-.009032,-.011019,
-.008107,-.011463,
-.007119,-.011739,
-.006097,-.01184,
-.00603,-.01184,
.00148,-.01184,
.00148,-.00948,
.01191,-.00948,
.01191,.00948,
.00148,.00948,
.00148,.01184,
-.00603,.01184,
-.007052,.011751,
-.008044,.011486,
-.008974,.011053,
-.009815,.010465,
-.010541,.00974,
-.01113,.0089,
-.011564,.00797,
-.01183,.006979,
-.01192,.005957,
-.01192,.00589,
-.01192,-.00589,
0.0*
%
%ADD29MACRO29*%
%AMMACRO19*
4,1,28,.00589,-.01192,
.006913,-.011842,
.007907,-.011587,
.008842,-.011163,
.009688,-.010584,
.010422,-.009866,
.011019,-.009032,
.011463,-.008107,
.011739,-.007119,
.01184,-.006097,
.01184,-.00603,
.01184,.00148,
.00948,.00148,
.00948,.01191,
-.00948,.01191,
-.00948,.00148,
-.01184,.00148,
-.01184,-.00603,
-.011751,-.007052,
-.011486,-.008044,
-.011053,-.008974,
-.010465,-.009815,
-.00974,-.010541,
-.0089,-.01113,
-.00797,-.011564,
-.006979,-.01183,
-.005957,-.01192,
-.00589,-.01192,
.00589,-.01192,
0.0*
%
%ADD19MACRO19*%
%AMMACRO28*
4,1,28,.01191,.0059,
.01183,.006923,
.011573,.007916,
.011148,.00885,
.010567,.009696,
.009849,.010428,
.009013,.011024,
.008088,.011466,
.007099,.011741,
.006078,.01184,
.00602,.01184,
-.00149,.01184,
-.00149,.00948,
-.01192,.00948,
-.01192,-.00948,
-.00149,-.00948,
-.00149,-.01184,
.00602,-.01184,
.007042,-.011751,
.008033,-.011486,
.008964,-.011053,
.009805,-.010465,
.010531,-.00974,
.01112,-.0089,
.011554,-.007971,
.01182,-.00698,
.01191,-.005958,
.01191,-.0059,
.01191,.0059,
0.0*
%
%ADD28MACRO28*%
%AMMACRO20*
4,1,28,-.0059,.01191,
-.006923,.01183,
-.007916,.011573,
-.00885,.011148,
-.009696,.010567,
-.010428,.009849,
-.011024,.009013,
-.011466,.008088,
-.011741,.007099,
-.01184,.006078,
-.01184,.00602,
-.01184,-.00149,
-.00948,-.00149,
-.00948,-.01192,
.00948,-.01192,
.00948,-.00149,
.01184,-.00149,
.01184,.00602,
.011751,.007042,
.011486,.008033,
.011053,.008964,
.010465,.009805,
.00974,.010531,
.0089,.01112,
.007971,.011554,
.00698,.01182,
.005958,.01191,
.0059,.01191,
-.0059,.01191,
0.0*
%
%ADD20MACRO20*%
%ADD103C,.02*%
%ADD104C,.006*%
G75*
%LPD*%
G75*
G36*
G01X26772Y1574425D02*
G02Y1560220I0J-7103D01*
G01X20472D01*
G02Y1574425I0J7102D01*
G01X26772D01*
G37*
G36*
G01X790357Y1490945D02*
G02I-19885J0D01*
G37*
G36*
G01X839964Y388583D02*
G02I-19885J0D01*
G37*
G36*
G01X1040751D02*
G02I-19885J0D01*
G37*
G36*
G01X1090357Y1490945D02*
G02I-19885J0D01*
G37*
G36*
G01X1824425Y53543D02*
G02X1810220I-7103J0D01*
G01Y59843D01*
G02X1824425I7102J0D01*
G01Y53543D01*
G37*
G36*
G01X1827373Y1567323D02*
G02I-10050J0D01*
G37*
G54D100*
X1795453Y812874D03*
Y834922D03*
G54D101*
X1803917Y823898D03*
G54D102*
X1817323Y1567323D03*
G54D103*
G01X0Y7874D02*
G03X7874Y0I7874J0D01*
G01X0Y323353D02*
Y7874D01*
G01X12654Y339269D02*
X2306Y328920D01*
G01D02*
G03X0Y323353I5567J-5567D01*
G01Y1640118D02*
Y970427D01*
G01D02*
G03X2306Y964859I7874J0D01*
G01D02*
X12654Y954511D01*
G01X7874Y1647992D02*
G03X0Y1640118I0J-7874D01*
G01X7874Y0D02*
X23484D01*
G01X14961Y948943D02*
Y344836D01*
G01D02*
G02X12654Y339269I-7873J1D01*
G01Y954511D02*
G02X14961Y948943I-5568J-5569D01*
G01X789297Y1647992D02*
X7874D01*
G01X23484Y0D02*
G03X31358Y7874I0J7874D01*
G01D02*
Y46654D01*
G01D02*
G02X35295Y50591I3937J0D01*
G01D02*
X66791D01*
G01D02*
G02X70728Y46654I0J-3937D01*
G01Y7874D02*
G03X78602Y0I7874J0D01*
G01D02*
X125846D01*
G01X70728Y46654D02*
Y7874D01*
G01X125846Y0D02*
G03X133720Y7874I0J7874D01*
G01D02*
Y46654D01*
G01D02*
G02X137657Y50591I3937J0D01*
G01D02*
X169154D01*
G01X173091Y7874D02*
G03X180965Y0I7874J0D01*
G01D02*
X228209D01*
G01X173091Y46654D02*
Y7874D01*
G01X169154Y50591D02*
G02X173091Y46654I0J-3937D01*
G01X228209Y0D02*
G03X236083Y7874I0J7874D01*
G01D02*
Y46654D01*
G01D02*
G02X240020Y50591I3937J0D01*
G01D02*
X271516D01*
G01X275453Y7874D02*
G03X283327Y0I7874J0D01*
G01X275453Y46654D02*
Y7874D01*
G01X271516Y50591D02*
G02X275453Y46654I0J-3937D01*
G01X283327Y0D02*
X330571D01*
G01D02*
G03X338445Y7874I0J7874D01*
G01D02*
Y46654D01*
G01D02*
G02X342382Y50591I3937J0D01*
G01D02*
X373878D01*
G01D02*
G02X377815Y46654I0J-3937D01*
G01Y7874D02*
G03X385689Y0I7874J0D01*
G01D02*
X480571D01*
G01X377815Y46654D02*
Y7874D01*
G01X480571Y0D02*
G03X488445Y7874I0J7874D01*
G01D02*
Y46654D01*
G01D02*
G02X492382Y50591I3937J0D01*
G01D02*
X523878D01*
G01X527815Y7874D02*
G03X535689Y0I7874J0D01*
G01D02*
X582933D01*
G01X527815Y46654D02*
Y7874D01*
G01X523878Y50591D02*
G02X527815Y46654I0J-3937D01*
G01X582933Y0D02*
G03X590807Y7874I0J7874D01*
G01D02*
Y46654D01*
G01D02*
G02X594744Y50591I3937J0D01*
G01D02*
X626240D01*
G01X630177Y7874D02*
G03X638051Y0I7874J0D01*
G01X630177Y46654D02*
Y7874D01*
G01X626240Y50591D02*
G02X630177Y46654I0J-3937D01*
G01X638051Y0D02*
X685295D01*
G01D02*
G03X693169Y7874I0J7874D01*
G01D02*
Y46654D01*
G01D02*
G02X697106Y50591I3937J0D01*
G01D02*
X728602D01*
G01X732539Y7874D02*
G03X740413Y0I7874J0D01*
G01X732539Y46654D02*
Y7874D01*
G01X728602Y50591D02*
G02X732539Y46654I0J-3937D01*
G01X740413Y0D02*
X787657D01*
G01D02*
G03X795531Y7874I0J7874D01*
G01D02*
Y46654D01*
G01X799469Y50591D02*
X830965D01*
G01X795531Y46654D02*
G02X799469Y50591I3937J0D01*
G01X800966Y1642819D02*
G02X795131Y1645406I0J7875D01*
G01D02*
G03X789297Y1647992I-5834J-5287D01*
G01X1070058Y1642819D02*
X800966D01*
G01X830965Y50591D02*
G02X834902Y46654I0J-3937D01*
G01Y7874D02*
G03X842776Y0I7874J0D01*
G01D02*
X937657D01*
G01X834902Y46654D02*
Y7874D01*
G01X937657Y0D02*
G03X945531Y7874I0J7874D01*
G01D02*
Y46654D01*
G01D02*
G02X949469Y50591I3938J0D01*
G01D02*
X980965D01*
G01X984902Y7874D02*
G03X992776Y0I7874J0D01*
G01D02*
X1040020D01*
G01X984902Y46654D02*
Y7874D01*
G01X980965Y50591D02*
G02X984902Y46654I0J-3937D01*
G01X1040020Y0D02*
G03X1047894Y7874I0J7874D01*
G01D02*
Y46654D01*
G01D02*
G02X1051831Y50591I3937J0D01*
G01D02*
X1083327D01*
G01X1075892Y1645406D02*
G02X1070058Y1642819I-5835J5286D01*
G01X1087264Y7874D02*
G03X1095138Y0I7874J0D01*
G01X1087264Y46654D02*
Y7874D01*
G01X1083327Y50591D02*
G02X1087264Y46654I0J-3937D01*
G01X1833071Y1647992D02*
X1081727D01*
G01D02*
G03X1075892Y1645406I-1J-7874D01*
G01X1095138Y0D02*
X1142382D01*
G01D02*
G03X1150256Y7874I0J7874D01*
G01D02*
Y46654D01*
G01D02*
G02X1154193Y50591I3937J0D01*
G01D02*
X1185689D01*
G01D02*
G02X1189626Y46654I0J-3937D01*
G01Y7874D02*
G03X1197500Y0I7874J0D01*
G01D02*
X1244744D01*
G01X1189626Y46654D02*
Y7874D01*
G01X1244744Y0D02*
G03X1252618Y7874I0J7874D01*
G01D02*
Y46654D01*
G01D02*
G02X1256555Y50591I3937J0D01*
G01D02*
X1288051D01*
G01X1291988Y7874D02*
G03X1299862Y0I7874J0D01*
G01D02*
X1394744D01*
G01X1291988Y46654D02*
Y7874D01*
G01X1288051Y50591D02*
G02X1291988Y46654I0J-3937D01*
G01X1394744Y0D02*
G03X1402618Y7874I0J7874D01*
G01D02*
Y46654D01*
G01D02*
G02X1406555Y50591I3937J0D01*
G01D02*
X1438051D01*
G01X1441988Y7874D02*
G03X1449862Y0I7874J0D01*
G01X1441988Y46654D02*
Y7874D01*
G01X1438051Y50591D02*
G02X1441988Y46654I0J-3937D01*
G01X1449862Y0D02*
X1497106D01*
G01D02*
G03X1504980Y7874I0J7874D01*
G01D02*
Y46654D01*
G01D02*
G02X1508917Y50591I3937J0D01*
G01D02*
X1540413D01*
G01X1544350Y7874D02*
G03X1552224Y0I7874J0D01*
G01X1544350Y46654D02*
Y7874D01*
G01X1540413Y50591D02*
G02X1544350Y46654I0J-3937D01*
G01X1552224Y0D02*
X1599469D01*
G01D02*
G03X1607343Y7874I0J7874D01*
G01D02*
Y46654D01*
G01X1611280Y50591D02*
X1642776D01*
G01X1607343Y46654D02*
G02X1611280Y50591I3937J0D01*
G01X1642776D02*
G02X1646713Y46654I0J-3937D01*
G01Y7874D02*
G03X1654587Y0I7874J0D01*
G01D02*
X1701831D01*
G01X1646713Y46654D02*
Y7874D01*
G01X1701831Y0D02*
G03X1709705Y7874I0J7874D01*
G01D02*
Y46654D01*
G01D02*
G02X1713642Y50591I3937J0D01*
G01D02*
X1745138D01*
G01X1749075Y7874D02*
G03X1756949Y0I7874J0D01*
G01D02*
X1833071D01*
G01X1749075Y46654D02*
Y7874D01*
G01X1745138Y50591D02*
G02X1749075Y46654I0J-3937D01*
G01X1833071Y0D02*
G03X1840945Y7874I0J7874D01*
G01Y323353D02*
G03X1838639Y328920I-7873J0D01*
G01X1825984Y344836D02*
Y948943D01*
G01X1838639Y328920D02*
X1828290Y339269D01*
G01D02*
G02X1825984Y344836I5567J5567D01*
G01Y948943D02*
G02X1828290Y954511I7874J0D01*
G01D02*
X1838639Y964859D01*
G01D02*
G03X1840945Y970427I-5568J5568D01*
G01Y1640118D02*
G03X1833071Y1647992I-7874J0D01*
G01X1840945Y7874D02*
Y323353D01*
G01Y970427D02*
Y1640118D01*
G54D10*
X13780Y1226024D03*
X79331Y1186654D03*
X235433Y1606142D03*
X390354Y1141024D03*
X536418Y1086654D03*
X581890Y1606142D03*
X854291Y1225118D03*
X993504Y1170748D03*
X1259055Y1606142D03*
X1304528Y1141024D03*
X1450591Y1086654D03*
X1605512Y1606142D03*
X1761614Y1215000D03*
X1827165Y1235630D03*
G54D104*
G01X-20602Y-468335D02*
Y-543335D01*
X479398D01*
Y-468335D01*
X-20602D01*
G01X-8602Y-533335D02*
Y-538335D01*
G01X-10059Y-533335D02*
X-7145D01*
G01X-2235Y-538335D02*
X-4769D01*
Y-533335D01*
X-2235D01*
G01X-3249Y-535752D02*
X-4769D01*
G01X331Y-533335D02*
Y-538335D01*
X2865D01*
G01X6698Y-538502D02*
X6571Y-538418D01*
Y-538252D01*
X6698Y-538168D01*
X6825Y-538252D01*
Y-538418D01*
X6698Y-538502D01*
G01Y-536252D02*
X6571Y-536168D01*
Y-536002D01*
X6698Y-535918D01*
X6825Y-536002D01*
Y-536168D01*
X6698Y-536252D01*
G01X11481Y-540002D02*
X10848Y-539168D01*
X10531Y-538335D01*
Y-535002D01*
X10848Y-534168D01*
X11481Y-533335D01*
G01X16898D02*
X16391Y-533502D01*
X16011Y-533918D01*
X15758Y-534418D01*
X15568Y-535085D01*
X15505Y-535835D01*
X15568Y-536585D01*
X15758Y-537252D01*
X16011Y-537752D01*
X16391Y-538168D01*
X16898Y-538335D01*
X17405Y-538168D01*
X17785Y-537752D01*
X18038Y-537252D01*
X18228Y-536585D01*
X18291Y-535835D01*
X18228Y-535085D01*
X18038Y-534418D01*
X17785Y-533918D01*
X17405Y-533502D01*
X16898Y-533335D01*
G01X20605Y-537335D02*
X20985Y-537918D01*
X21491Y-538252D01*
X22061Y-538335D01*
X22568Y-538252D01*
X23075Y-537835D01*
X23391Y-537335D01*
X23455Y-536835D01*
X23328Y-536252D01*
X22885Y-535835D01*
X22441Y-535668D01*
X21871D01*
G01X22441D02*
X22821Y-535418D01*
X23138Y-535002D01*
X23265Y-534502D01*
X23138Y-534002D01*
X22821Y-533585D01*
X22251Y-533335D01*
X21681Y-533418D01*
X21111Y-533752D01*
G01X27415Y-540002D02*
X28048Y-539168D01*
X28365Y-538335D01*
Y-535002D01*
X28048Y-534168D01*
X27415Y-533335D01*
G01X30805Y-537335D02*
X31185Y-537918D01*
X31691Y-538252D01*
X32261Y-538335D01*
X32768Y-538252D01*
X33275Y-537835D01*
X33591Y-537335D01*
X33655Y-536835D01*
X33528Y-536252D01*
X33085Y-535835D01*
X32641Y-535668D01*
X32071D01*
G01X32641D02*
X33021Y-535418D01*
X33338Y-535002D01*
X33465Y-534502D01*
X33338Y-534002D01*
X33021Y-533585D01*
X32451Y-533335D01*
X31881Y-533418D01*
X31311Y-533752D01*
G01X36095Y-534168D02*
X36475Y-533668D01*
X36918Y-533418D01*
X37425Y-533335D01*
X38058Y-533502D01*
X38501Y-533918D01*
X38628Y-534418D01*
X38565Y-534918D01*
X38311Y-535335D01*
X37045Y-536168D01*
X36475Y-536752D01*
X36095Y-537585D01*
X35968Y-538335D01*
X38628D01*
G01X42271D02*
X42398Y-537252D01*
X42588Y-536335D01*
X42841Y-535502D01*
X43158Y-534585D01*
X43665Y-533335D01*
X41131D01*
G01X46675Y-536668D02*
X48321D01*
G01X51395Y-534168D02*
X51775Y-533668D01*
X52218Y-533418D01*
X52725Y-533335D01*
X53358Y-533502D01*
X53801Y-533918D01*
X53928Y-534418D01*
X53865Y-534918D01*
X53611Y-535335D01*
X52345Y-536168D01*
X51775Y-536752D01*
X51395Y-537585D01*
X51268Y-538335D01*
X53928D01*
G01X56305Y-537335D02*
X56685Y-537918D01*
X57191Y-538252D01*
X57761Y-538335D01*
X58268Y-538252D01*
X58775Y-537835D01*
X59091Y-537335D01*
X59155Y-536835D01*
X59028Y-536252D01*
X58585Y-535835D01*
X58141Y-535668D01*
X57571D01*
G01X58141D02*
X58521Y-535418D01*
X58838Y-535002D01*
X58965Y-534502D01*
X58838Y-534002D01*
X58521Y-533585D01*
X57951Y-533335D01*
X57381Y-533418D01*
X56811Y-533752D01*
G01X63558Y-538335D02*
Y-533335D01*
X61215Y-536918D01*
X64381D01*
G01X66505Y-537585D02*
X66885Y-538002D01*
X67328Y-538252D01*
X67898Y-538335D01*
X68468Y-538168D01*
X68911Y-537835D01*
X69228Y-537252D01*
X69291Y-536585D01*
X69165Y-535918D01*
X68848Y-535502D01*
X68405Y-535168D01*
X67961Y-535085D01*
X67518Y-535168D01*
X66948Y-535502D01*
X67138Y-533335D01*
X68848D01*
G01X76895Y-538335D02*
Y-533335D01*
X79301D01*
G01X78415Y-535752D02*
X76895D01*
G01X81615Y-538335D02*
X83198Y-533335D01*
X84781Y-538335D01*
G01X84211Y-536585D02*
X82185D01*
G01X86968Y-538335D02*
X89628Y-533335D01*
G01X86968D02*
X89628Y-538335D01*
G01X93398Y-538502D02*
X93271Y-538418D01*
Y-538252D01*
X93398Y-538168D01*
X93525Y-538252D01*
Y-538418D01*
X93398Y-538502D01*
G01Y-536252D02*
X93271Y-536168D01*
Y-536002D01*
X93398Y-535918D01*
X93525Y-536002D01*
Y-536168D01*
X93398Y-536252D01*
G01X98181Y-540002D02*
X97548Y-539168D01*
X97231Y-538335D01*
Y-535002D01*
X97548Y-534168D01*
X98181Y-533335D01*
G01X103598D02*
X103091Y-533502D01*
X102711Y-533918D01*
X102458Y-534418D01*
X102268Y-535085D01*
X102205Y-535835D01*
X102268Y-536585D01*
X102458Y-537252D01*
X102711Y-537752D01*
X103091Y-538168D01*
X103598Y-538335D01*
X104105Y-538168D01*
X104485Y-537752D01*
X104738Y-537252D01*
X104928Y-536585D01*
X104991Y-535835D01*
X104928Y-535085D01*
X104738Y-534418D01*
X104485Y-533918D01*
X104105Y-533502D01*
X103598Y-533335D01*
G01X107305Y-537335D02*
X107685Y-537918D01*
X108191Y-538252D01*
X108761Y-538335D01*
X109268Y-538252D01*
X109775Y-537835D01*
X110091Y-537335D01*
X110155Y-536835D01*
X110028Y-536252D01*
X109585Y-535835D01*
X109141Y-535668D01*
X108571D01*
G01X109141D02*
X109521Y-535418D01*
X109838Y-535002D01*
X109965Y-534502D01*
X109838Y-534002D01*
X109521Y-533585D01*
X108951Y-533335D01*
X108381Y-533418D01*
X107811Y-533752D01*
G01X114115Y-540002D02*
X114748Y-539168D01*
X115065Y-538335D01*
Y-535002D01*
X114748Y-534168D01*
X114115Y-533335D01*
G01X117505Y-537335D02*
X117885Y-537918D01*
X118391Y-538252D01*
X118961Y-538335D01*
X119468Y-538252D01*
X119975Y-537835D01*
X120291Y-537335D01*
X120355Y-536835D01*
X120228Y-536252D01*
X119785Y-535835D01*
X119341Y-535668D01*
X118771D01*
G01X119341D02*
X119721Y-535418D01*
X120038Y-535002D01*
X120165Y-534502D01*
X120038Y-534002D01*
X119721Y-533585D01*
X119151Y-533335D01*
X118581Y-533418D01*
X118011Y-533752D01*
G01X122921Y-537752D02*
X123365Y-538168D01*
X123871Y-538335D01*
X124378Y-538168D01*
X124821Y-537668D01*
X125138Y-536918D01*
X125265Y-536168D01*
Y-535252D01*
X125138Y-534502D01*
X124821Y-533835D01*
X124441Y-533502D01*
X123998Y-533335D01*
X123491Y-533502D01*
X123111Y-533835D01*
X122858Y-534335D01*
X122731Y-535002D01*
X122858Y-535585D01*
X123175Y-536168D01*
X123555Y-536502D01*
X123998Y-536585D01*
X124505Y-536418D01*
X124885Y-536002D01*
X125265Y-535252D01*
G01X128971Y-538335D02*
X129098Y-537252D01*
X129288Y-536335D01*
X129541Y-535502D01*
X129858Y-534585D01*
X130365Y-533335D01*
X127831D01*
G01X133375Y-536668D02*
X135021D01*
G01X137905Y-537335D02*
X138285Y-537918D01*
X138791Y-538252D01*
X139361Y-538335D01*
X139868Y-538252D01*
X140375Y-537835D01*
X140691Y-537335D01*
X140755Y-536835D01*
X140628Y-536252D01*
X140185Y-535835D01*
X139741Y-535668D01*
X139171D01*
G01X139741D02*
X140121Y-535418D01*
X140438Y-535002D01*
X140565Y-534502D01*
X140438Y-534002D01*
X140121Y-533585D01*
X139551Y-533335D01*
X138981Y-533418D01*
X138411Y-533752D01*
G01X143195Y-536252D02*
X143638Y-535668D01*
X144018Y-535335D01*
X144525Y-535168D01*
X144968Y-535335D01*
X145285Y-535668D01*
X145538Y-536168D01*
X145601Y-536752D01*
X145538Y-537252D01*
X145285Y-537752D01*
X144905Y-538168D01*
X144461Y-538335D01*
X143955Y-538168D01*
X143511Y-537668D01*
X143258Y-536918D01*
X143195Y-536085D01*
X143321Y-535002D01*
X143511Y-534418D01*
X143828Y-533835D01*
X144271Y-533418D01*
X144715Y-533335D01*
X145158Y-533502D01*
X145475Y-533918D01*
G01X149498Y-538335D02*
Y-533335D01*
X148738Y-534335D01*
G01Y-538335D02*
X150258D01*
G01X155358D02*
Y-533335D01*
X153015Y-536918D01*
X156181D01*
G01X174398Y-468335D02*
Y-543335D01*
G01Y-518335D02*
X277398D01*
Y-493335D01*
G01X174398D02*
X277398D01*
G01Y-468335D02*
Y-543335D01*
G01X279398Y-468335D02*
Y-543335D01*
G01X284905Y-528335D02*
Y-523335D01*
X286171D01*
X286678Y-523585D01*
X287058Y-523918D01*
X287375Y-524418D01*
X287628Y-525002D01*
X287691Y-525835D01*
X287628Y-526668D01*
X287375Y-527252D01*
X287058Y-527752D01*
X286678Y-528085D01*
X286171Y-528335D01*
X284905D01*
G01X289815D02*
X291398Y-523335D01*
X292981Y-528335D01*
G01X292411Y-526585D02*
X290385D01*
G01X296498Y-523335D02*
Y-528335D01*
G01X295041Y-523335D02*
X297955D01*
G01X302865Y-528335D02*
X300331D01*
Y-523335D01*
X302865D01*
G01X301851Y-525752D02*
X300331D01*
G01X306698Y-528502D02*
X306571Y-528418D01*
Y-528252D01*
X306698Y-528168D01*
X306825Y-528252D01*
Y-528418D01*
X306698Y-528502D01*
G01Y-526252D02*
X306571Y-526168D01*
Y-526002D01*
X306698Y-525918D01*
X306825Y-526002D01*
Y-526168D01*
X306698Y-526252D01*
G01X279398Y-518335D02*
X479398D01*
G01X285031Y-503335D02*
Y-498335D01*
X286551D01*
X287058Y-498585D01*
X287438Y-499168D01*
X287565Y-499835D01*
X287438Y-500502D01*
X287121Y-501002D01*
X286551Y-501252D01*
X285031D01*
G01X290258Y-503502D02*
X292538Y-498335D01*
G01X295041Y-503335D02*
Y-498335D01*
X297955Y-503335D01*
Y-498335D01*
G01X301598Y-503502D02*
X301471Y-503418D01*
Y-503252D01*
X301598Y-503168D01*
X301725Y-503252D01*
Y-503418D01*
X301598Y-503502D01*
G01Y-501252D02*
X301471Y-501168D01*
Y-501002D01*
X301598Y-500918D01*
X301725Y-501002D01*
Y-501168D01*
X301598Y-501252D01*
G01X279398Y-493335D02*
X479398D01*
G01X285031Y-478335D02*
Y-473335D01*
X286551D01*
X287058Y-473585D01*
X287438Y-474168D01*
X287565Y-474835D01*
X287438Y-475502D01*
X287121Y-476002D01*
X286551Y-476252D01*
X285031D01*
G01X290131Y-478335D02*
Y-473335D01*
X291715D01*
X292221Y-473585D01*
X292538Y-473918D01*
X292665Y-474585D01*
X292538Y-475252D01*
X292158Y-475668D01*
X291715Y-475918D01*
X290131D01*
G01X291715D02*
X292665Y-478335D01*
G01X296498D02*
X295991Y-478252D01*
X295548Y-477918D01*
X295168Y-477418D01*
X294915Y-476835D01*
X294788Y-476168D01*
Y-475502D01*
X294915Y-474835D01*
X295168Y-474252D01*
X295548Y-473752D01*
X295991Y-473418D01*
X296498Y-473335D01*
X297005Y-473418D01*
X297448Y-473752D01*
X297828Y-474252D01*
X298081Y-474835D01*
X298208Y-475502D01*
Y-476168D01*
X298081Y-476835D01*
X297828Y-477418D01*
X297448Y-477918D01*
X297005Y-478252D01*
X296498Y-478335D01*
G01X300331Y-477335D02*
X300648Y-477835D01*
X301028Y-478168D01*
X301471Y-478335D01*
X301978Y-478168D01*
X302358Y-477835D01*
X302738Y-477335D01*
X302865Y-476668D01*
Y-473335D01*
G01X307965Y-478335D02*
X305431D01*
Y-473335D01*
X307965D01*
G01X306951Y-475752D02*
X305431D01*
G01X313191Y-473752D02*
X312811Y-473502D01*
X312368Y-473335D01*
X311861D01*
X311291Y-473585D01*
X310848Y-474002D01*
X310531Y-474502D01*
X310278Y-475335D01*
X310215Y-476085D01*
X310341Y-476835D01*
X310531Y-477335D01*
X310911Y-477835D01*
X311355Y-478168D01*
X311798Y-478335D01*
X312241D01*
X312685Y-478168D01*
X313065Y-477918D01*
X313381Y-477585D01*
G01X316898Y-473335D02*
Y-478335D01*
G01X315441Y-473335D02*
X318355D01*
G01X321998Y-478502D02*
X321871Y-478418D01*
Y-478252D01*
X321998Y-478168D01*
X322125Y-478252D01*
Y-478418D01*
X321998Y-478502D01*
G01Y-476252D02*
X321871Y-476168D01*
Y-476002D01*
X321998Y-475918D01*
X322125Y-476002D01*
Y-476168D01*
X321998Y-476252D01*
G01X394258Y-543563D02*
Y-518563D01*
G01X397031Y-520835D02*
Y-525835D01*
X399565D01*
G01X402638Y-520835D02*
X404158D01*
G01X403398D02*
Y-525835D01*
G01X402638D02*
X404158D01*
G01X409005Y-523168D02*
X409258Y-522918D01*
X409448Y-522502D01*
X409575Y-521918D01*
X409448Y-521418D01*
X409195Y-521085D01*
X408751Y-520835D01*
X407041D01*
Y-525835D01*
X409131D01*
X409575Y-525502D01*
X409828Y-525002D01*
X409955Y-524418D01*
X409828Y-523835D01*
X409448Y-523335D01*
X409005Y-523168D01*
X407041D01*
G01X413598Y-526002D02*
X413471Y-525918D01*
Y-525752D01*
X413598Y-525668D01*
X413725Y-525752D01*
Y-525918D01*
X413598Y-526002D01*
G01Y-523752D02*
X413471Y-523668D01*
Y-523502D01*
X413598Y-523418D01*
X413725Y-523502D01*
Y-523668D01*
X413598Y-523752D01*
G01X437258Y-518563D02*
Y-543563D01*
G01X437398Y-518335D02*
Y-543335D01*
G01X441298Y-520835D02*
Y-525835D01*
G01X439841Y-520835D02*
X442755D01*
G01X446398Y-525835D02*
X446018Y-525752D01*
X445638Y-525418D01*
X445385Y-524835D01*
X445258Y-524168D01*
X445385Y-523502D01*
X445638Y-522918D01*
X446018Y-522585D01*
X446398Y-522502D01*
X446778Y-522585D01*
X447158Y-522918D01*
X447411Y-523502D01*
X447475Y-524168D01*
X447411Y-524835D01*
X447158Y-525418D01*
X446778Y-525752D01*
X446398Y-525835D01*
G01X451498D02*
X451118Y-525752D01*
X450738Y-525418D01*
X450485Y-524835D01*
X450358Y-524168D01*
X450485Y-523502D01*
X450738Y-522918D01*
X451118Y-522585D01*
X451498Y-522502D01*
X451878Y-522585D01*
X452258Y-522918D01*
X452511Y-523502D01*
X452575Y-524168D01*
X452511Y-524835D01*
X452258Y-525418D01*
X451878Y-525752D01*
X451498Y-525835D01*
G01X456598D02*
Y-520835D01*
G01X461698Y-526002D02*
X461571Y-525918D01*
Y-525752D01*
X461698Y-525668D01*
X461825Y-525752D01*
Y-525918D01*
X461698Y-526002D01*
G01Y-523752D02*
X461571Y-523668D01*
Y-523502D01*
X461698Y-523418D01*
X461825Y-523502D01*
Y-523668D01*
X461698Y-523752D01*
G01X437398Y-493335D02*
Y-518335D01*
G01X440031Y-500835D02*
Y-495835D01*
X441615D01*
X442121Y-496085D01*
X442438Y-496418D01*
X442565Y-497085D01*
X442438Y-497752D01*
X442058Y-498168D01*
X441615Y-498418D01*
X440031D01*
G01X441615D02*
X442565Y-500835D01*
G01X447665D02*
X445131D01*
Y-495835D01*
X447665D01*
G01X446651Y-498252D02*
X445131D01*
G01X449915Y-495835D02*
X451498Y-500835D01*
X453081Y-495835D01*
G01X456598Y-501002D02*
X456471Y-500918D01*
Y-500752D01*
X456598Y-500668D01*
X456725Y-500752D01*
Y-500918D01*
X456598Y-501002D01*
G01Y-498752D02*
X456471Y-498668D01*
Y-498502D01*
X456598Y-498418D01*
X456725Y-498502D01*
Y-498668D01*
X456598Y-498752D01*
G01X445411Y-546502D02*
X445518Y-546377D01*
X445598Y-546168D01*
X445651Y-545877D01*
X445598Y-545627D01*
X445491Y-545460D01*
X445305Y-545335D01*
X444585D01*
Y-547835D01*
X445465D01*
X445651Y-547668D01*
X445758Y-547418D01*
X445811Y-547127D01*
X445758Y-546835D01*
X445598Y-546585D01*
X445411Y-546502D01*
X444585D01*
G01X447878Y-547835D02*
Y-546168D01*
G01Y-546460D02*
X447771Y-546293D01*
X447611Y-546210D01*
X447425Y-546168D01*
X447238Y-546252D01*
X447078Y-546418D01*
X446971Y-546668D01*
X446918Y-547002D01*
X446971Y-547335D01*
X447078Y-547585D01*
X447238Y-547752D01*
X447425Y-547835D01*
X447611Y-547793D01*
X447771Y-547668D01*
X447878Y-547502D01*
G01X449198Y-547543D02*
X449331Y-547710D01*
X449518Y-547835D01*
X449678D01*
X449838Y-547752D01*
X449945Y-547627D01*
X449998Y-547460D01*
X449971Y-547210D01*
X449865Y-547085D01*
X449385Y-546835D01*
X449278Y-546543D01*
X449331Y-546335D01*
X449438Y-546210D01*
X449598Y-546168D01*
X449758Y-546210D01*
X449918Y-546335D01*
G01X451398Y-546710D02*
X452251D01*
X452171Y-546418D01*
X452038Y-546252D01*
X451851Y-546168D01*
X451665Y-546210D01*
X451505Y-546335D01*
X451398Y-546627D01*
X451345Y-546877D01*
Y-547127D01*
X451398Y-547377D01*
X451531Y-547627D01*
X451691Y-547793D01*
X451878Y-547835D01*
X452065Y-547752D01*
X452251Y-547502D01*
G01X453518Y-547835D02*
Y-545335D01*
G01Y-546585D02*
X453651Y-546335D01*
X453811Y-546210D01*
X453971Y-546168D01*
X454211Y-546252D01*
X454371Y-546418D01*
X454478Y-546710D01*
Y-547043D01*
X454425Y-547377D01*
X454318Y-547627D01*
X454131Y-547793D01*
X453971Y-547835D01*
X453811Y-547793D01*
X453651Y-547668D01*
X453518Y-547460D01*
G01X456198Y-547835D02*
X456038Y-547793D01*
X455878Y-547627D01*
X455771Y-547335D01*
X455718Y-547002D01*
X455771Y-546668D01*
X455878Y-546377D01*
X456038Y-546210D01*
X456198Y-546168D01*
X456358Y-546210D01*
X456518Y-546377D01*
X456625Y-546668D01*
X456651Y-547002D01*
X456625Y-547335D01*
X456518Y-547627D01*
X456358Y-547793D01*
X456198Y-547835D01*
G01X458878D02*
Y-546168D01*
G01Y-546460D02*
X458771Y-546293D01*
X458611Y-546210D01*
X458425Y-546168D01*
X458238Y-546252D01*
X458078Y-546418D01*
X457971Y-546668D01*
X457918Y-547002D01*
X457971Y-547335D01*
X458078Y-547585D01*
X458238Y-547752D01*
X458425Y-547835D01*
X458611Y-547793D01*
X458771Y-547668D01*
X458878Y-547502D01*
G01X460225Y-547835D02*
Y-546168D01*
G01Y-546502D02*
X460358Y-546335D01*
X460491Y-546210D01*
X460678Y-546168D01*
X460811Y-546210D01*
X460971Y-546335D01*
G01X463278Y-545335D02*
Y-547835D01*
G01Y-547460D02*
X463171Y-547668D01*
X463011Y-547793D01*
X462825Y-547835D01*
X462611Y-547752D01*
X462451Y-547543D01*
X462345Y-547293D01*
X462318Y-547002D01*
X462345Y-546710D01*
X462451Y-546460D01*
X462611Y-546252D01*
X462825Y-546168D01*
X463011Y-546210D01*
X463145Y-546293D01*
X463278Y-546460D01*
G01X466665Y-547835D02*
Y-545335D01*
X467331D01*
X467545Y-545460D01*
X467678Y-545627D01*
X467731Y-545960D01*
X467678Y-546293D01*
X467518Y-546502D01*
X467331Y-546627D01*
X466665D01*
G01X467331D02*
X467731Y-547835D01*
G01X468998Y-546710D02*
X469851D01*
X469771Y-546418D01*
X469638Y-546252D01*
X469451Y-546168D01*
X469265Y-546210D01*
X469105Y-546335D01*
X468998Y-546627D01*
X468945Y-546877D01*
Y-547127D01*
X468998Y-547377D01*
X469131Y-547627D01*
X469291Y-547793D01*
X469478Y-547835D01*
X469665Y-547752D01*
X469851Y-547502D01*
G01X471118Y-546168D02*
X471598Y-547835D01*
X472078Y-546168D01*
G01X473798Y-547918D02*
X473745Y-547877D01*
Y-547793D01*
X473798Y-547752D01*
X473851Y-547793D01*
Y-547877D01*
X473798Y-547918D01*
G01X475545Y-547543D02*
X475731Y-547752D01*
X475945Y-547835D01*
X476158Y-547752D01*
X476345Y-547502D01*
X476478Y-547127D01*
X476531Y-546752D01*
Y-546293D01*
X476478Y-545918D01*
X476345Y-545585D01*
X476185Y-545418D01*
X475998Y-545335D01*
X475785Y-545418D01*
X475625Y-545585D01*
X475518Y-545835D01*
X475465Y-546168D01*
X475518Y-546460D01*
X475651Y-546752D01*
X475811Y-546918D01*
X475998Y-546960D01*
X476211Y-546877D01*
X476371Y-546668D01*
X476531Y-546293D01*
G01X478411Y-546502D02*
X478518Y-546377D01*
X478598Y-546168D01*
X478651Y-545877D01*
X478598Y-545627D01*
X478491Y-545460D01*
X478305Y-545335D01*
X477585D01*
Y-547835D01*
X478465D01*
X478651Y-547668D01*
X478758Y-547418D01*
X478811Y-547127D01*
X478758Y-546835D01*
X478598Y-546585D01*
X478411Y-546502D01*
X477585D01*
G01X-1490433Y-1677216D02*
Y3837819D01*
X4496476D01*
Y-1677216D01*
X-1490433D01*
G01X-7782Y-515685D02*
X-6215D01*
Y-517575D01*
X-6685Y-518205D01*
X-7234Y-518625D01*
X-8017Y-518835D01*
X-8800Y-518625D01*
X-9349Y-518205D01*
X-9819Y-517575D01*
X-10132Y-516840D01*
X-10289Y-516000D01*
Y-515265D01*
X-10132Y-514635D01*
X-9819Y-513900D01*
X-9349Y-513270D01*
X-8879Y-512850D01*
X-8252Y-512535D01*
X-7704D01*
X-7077Y-512745D01*
X-6607Y-513165D01*
G01X-3675Y-512535D02*
Y-517050D01*
X-3362Y-517995D01*
X-2735Y-518625D01*
X-1952Y-518835D01*
X-1169Y-518625D01*
X-542Y-517995D01*
X-229Y-517050D01*
Y-512535D01*
G01X3408D02*
X5288D01*
G01X4348D02*
Y-518835D01*
G01X3408D02*
X5288D01*
G01X9003Y-517995D02*
X9630Y-518520D01*
X10335Y-518835D01*
X10961D01*
X11588Y-518520D01*
X12058Y-517995D01*
X12293Y-517260D01*
X12136Y-516525D01*
X11745Y-515895D01*
X11040Y-515475D01*
X10100Y-515265D01*
X9551Y-514845D01*
X9316Y-514110D01*
X9473Y-513375D01*
X9865Y-512850D01*
X10413Y-512535D01*
X10961D01*
X11510Y-512745D01*
X11980Y-513270D01*
G01X15303Y-518835D02*
Y-512535D01*
G01X18593D02*
Y-518835D01*
G01Y-515685D02*
X15303D01*
G01X21290Y-518835D02*
X23248Y-512535D01*
X25206Y-518835D01*
G01X24501Y-516630D02*
X21995D01*
G01X27746Y-518835D02*
Y-512535D01*
X31350Y-518835D01*
Y-512535D01*
G01X40425Y-518835D02*
Y-512535D01*
X41991D01*
X42618Y-512850D01*
X43088Y-513270D01*
X43480Y-513900D01*
X43793Y-514635D01*
X43871Y-515685D01*
X43793Y-516735D01*
X43480Y-517470D01*
X43088Y-518100D01*
X42618Y-518520D01*
X41991Y-518835D01*
X40425D01*
G01X47508Y-512535D02*
X49388D01*
G01X48448D02*
Y-518835D01*
G01X47508D02*
X49388D01*
G01X53103Y-517995D02*
X53730Y-518520D01*
X54435Y-518835D01*
X55061D01*
X55688Y-518520D01*
X56158Y-517995D01*
X56393Y-517260D01*
X56236Y-516525D01*
X55845Y-515895D01*
X55140Y-515475D01*
X54200Y-515265D01*
X53651Y-514845D01*
X53416Y-514110D01*
X53573Y-513375D01*
X53965Y-512850D01*
X54513Y-512535D01*
X55061D01*
X55610Y-512745D01*
X56080Y-513270D01*
G01X61048Y-512535D02*
Y-518835D01*
G01X59246Y-512535D02*
X62850D01*
G01X67348Y-519045D02*
X67191Y-518940D01*
Y-518730D01*
X67348Y-518625D01*
X67505Y-518730D01*
Y-518940D01*
X67348Y-519045D01*
G01X73491Y-519990D02*
X73805Y-518625D01*
G01X79948Y-512535D02*
Y-518835D01*
G01X78146Y-512535D02*
X81750D01*
G01X84290Y-518835D02*
X86248Y-512535D01*
X88206Y-518835D01*
G01X87501Y-516630D02*
X84995D01*
G01X92548Y-518835D02*
X91921Y-518730D01*
X91373Y-518310D01*
X90903Y-517680D01*
X90590Y-516945D01*
X90433Y-516105D01*
Y-515265D01*
X90590Y-514425D01*
X90903Y-513690D01*
X91373Y-513060D01*
X91921Y-512640D01*
X92548Y-512535D01*
X93175Y-512640D01*
X93723Y-513060D01*
X94193Y-513690D01*
X94506Y-514425D01*
X94663Y-515265D01*
Y-516105D01*
X94506Y-516945D01*
X94193Y-517680D01*
X93723Y-518310D01*
X93175Y-518730D01*
X92548Y-518835D01*
G01X98848D02*
Y-516000D01*
X97281Y-512535D01*
G01X100415D02*
X98848Y-516000D01*
G01X103425Y-512535D02*
Y-517050D01*
X103738Y-517995D01*
X104365Y-518625D01*
X105148Y-518835D01*
X105931Y-518625D01*
X106558Y-517995D01*
X106871Y-517050D01*
Y-512535D01*
G01X109490Y-518835D02*
X111448Y-512535D01*
X113406Y-518835D01*
G01X112701Y-516630D02*
X110195D01*
G01X115946Y-518835D02*
Y-512535D01*
X119550Y-518835D01*
Y-512535D01*
G01X-6529Y-523060D02*
X-6999Y-522745D01*
X-7547Y-522535D01*
X-8174D01*
X-8879Y-522850D01*
X-9427Y-523375D01*
X-9819Y-524005D01*
X-10132Y-525055D01*
X-10210Y-526000D01*
X-10054Y-526945D01*
X-9819Y-527575D01*
X-9349Y-528205D01*
X-8800Y-528625D01*
X-8252Y-528835D01*
X-7704D01*
X-7155Y-528625D01*
X-6685Y-528310D01*
X-6294Y-527890D01*
G01X-2892Y-522535D02*
X-1012D01*
G01X-1952D02*
Y-528835D01*
G01X-2892D02*
X-1012D01*
G01X4348Y-522535D02*
Y-528835D01*
G01X2546Y-522535D02*
X6150D01*
G01X10648Y-528835D02*
Y-526000D01*
X9081Y-522535D01*
G01X12215D02*
X10648Y-526000D01*
G01X21525Y-527575D02*
X21995Y-528310D01*
X22621Y-528730D01*
X23326Y-528835D01*
X23953Y-528730D01*
X24580Y-528205D01*
X24971Y-527575D01*
X25050Y-526945D01*
X24893Y-526210D01*
X24345Y-525685D01*
X23796Y-525475D01*
X23091D01*
G01X23796D02*
X24266Y-525160D01*
X24658Y-524635D01*
X24815Y-524005D01*
X24658Y-523375D01*
X24266Y-522850D01*
X23561Y-522535D01*
X22856Y-522640D01*
X22151Y-523060D01*
G01X27825Y-527575D02*
X28295Y-528310D01*
X28921Y-528730D01*
X29626Y-528835D01*
X30253Y-528730D01*
X30880Y-528205D01*
X31271Y-527575D01*
X31350Y-526945D01*
X31193Y-526210D01*
X30645Y-525685D01*
X30096Y-525475D01*
X29391D01*
G01X30096D02*
X30566Y-525160D01*
X30958Y-524635D01*
X31115Y-524005D01*
X30958Y-523375D01*
X30566Y-522850D01*
X29861Y-522535D01*
X29156Y-522640D01*
X28451Y-523060D01*
G01X34125Y-527575D02*
X34595Y-528310D01*
X35221Y-528730D01*
X35926Y-528835D01*
X36553Y-528730D01*
X37180Y-528205D01*
X37571Y-527575D01*
X37650Y-526945D01*
X37493Y-526210D01*
X36945Y-525685D01*
X36396Y-525475D01*
X35691D01*
G01X36396D02*
X36866Y-525160D01*
X37258Y-524635D01*
X37415Y-524005D01*
X37258Y-523375D01*
X36866Y-522850D01*
X36161Y-522535D01*
X35456Y-522640D01*
X34751Y-523060D01*
G01X41991Y-528835D02*
X42148Y-527470D01*
X42383Y-526315D01*
X42696Y-525265D01*
X43088Y-524110D01*
X43715Y-522535D01*
X40581D01*
G01X48291Y-528835D02*
X48448Y-527470D01*
X48683Y-526315D01*
X48996Y-525265D01*
X49388Y-524110D01*
X50015Y-522535D01*
X46881D01*
G01X54591Y-529990D02*
X54905Y-528625D01*
G01X61048Y-522535D02*
Y-528835D01*
G01X59246Y-522535D02*
X62850D01*
G01X65390Y-528835D02*
X67348Y-522535D01*
X69306Y-528835D01*
G01X68601Y-526630D02*
X66095D01*
G01X72708Y-522535D02*
X74588D01*
G01X73648D02*
Y-528835D01*
G01X72708D02*
X74588D01*
G01X77598Y-522535D02*
X78695Y-528835D01*
X79948Y-522535D01*
X81201Y-528835D01*
X82298Y-522535D01*
G01X84290Y-528835D02*
X86248Y-522535D01*
X88206Y-528835D01*
G01X87501Y-526630D02*
X84995D01*
G01X90746Y-528835D02*
Y-522535D01*
X94350Y-528835D01*
Y-522535D01*
G01X104756Y-530935D02*
X103973Y-529885D01*
X103581Y-528835D01*
Y-524635D01*
X103973Y-523585D01*
X104756Y-522535D01*
G01X116181Y-528835D02*
Y-522535D01*
X118140D01*
X118766Y-522850D01*
X119158Y-523270D01*
X119315Y-524110D01*
X119158Y-524950D01*
X118688Y-525475D01*
X118140Y-525790D01*
X116181D01*
G01X118140D02*
X119315Y-528835D01*
G01X124048Y-529045D02*
X123891Y-528940D01*
Y-528730D01*
X124048Y-528625D01*
X124205Y-528730D01*
Y-528940D01*
X124048Y-529045D01*
G01X130348Y-528835D02*
X129721Y-528730D01*
X129173Y-528310D01*
X128703Y-527680D01*
X128390Y-526945D01*
X128233Y-526105D01*
Y-525265D01*
X128390Y-524425D01*
X128703Y-523690D01*
X129173Y-523060D01*
X129721Y-522640D01*
X130348Y-522535D01*
X130975Y-522640D01*
X131523Y-523060D01*
X131993Y-523690D01*
X132306Y-524425D01*
X132463Y-525265D01*
Y-526105D01*
X132306Y-526945D01*
X131993Y-527680D01*
X131523Y-528310D01*
X130975Y-528730D01*
X130348Y-528835D01*
G01X136648Y-529045D02*
X136491Y-528940D01*
Y-528730D01*
X136648Y-528625D01*
X136805Y-528730D01*
Y-528940D01*
X136648Y-529045D01*
G01X144671Y-523060D02*
X144201Y-522745D01*
X143653Y-522535D01*
X143026D01*
X142321Y-522850D01*
X141773Y-523375D01*
X141381Y-524005D01*
X141068Y-525055D01*
X140990Y-526000D01*
X141146Y-526945D01*
X141381Y-527575D01*
X141851Y-528205D01*
X142400Y-528625D01*
X142948Y-528835D01*
X143496D01*
X144045Y-528625D01*
X144515Y-528310D01*
X144906Y-527890D01*
G01X149248Y-529045D02*
X149091Y-528940D01*
Y-528730D01*
X149248Y-528625D01*
X149405Y-528730D01*
Y-528940D01*
X149248Y-529045D01*
G01X155940Y-530935D02*
X156723Y-529885D01*
X157115Y-528835D01*
Y-524635D01*
X156723Y-523585D01*
X155940Y-522535D01*
G01X-10054Y-508835D02*
Y-502535D01*
X-6450Y-508835D01*
Y-502535D01*
G01X-1952Y-508835D02*
X-2579Y-508730D01*
X-3127Y-508310D01*
X-3597Y-507680D01*
X-3910Y-506945D01*
X-4067Y-506105D01*
Y-505265D01*
X-3910Y-504425D01*
X-3597Y-503690D01*
X-3127Y-503060D01*
X-2579Y-502640D01*
X-1952Y-502535D01*
X-1325Y-502640D01*
X-777Y-503060D01*
X-307Y-503690D01*
X6Y-504425D01*
X163Y-505265D01*
Y-506105D01*
X6Y-506945D01*
X-307Y-507680D01*
X-777Y-508310D01*
X-1325Y-508730D01*
X-1952Y-508835D01*
G01X4348Y-509045D02*
X4191Y-508940D01*
Y-508730D01*
X4348Y-508625D01*
X4505Y-508730D01*
Y-508940D01*
X4348Y-509045D01*
G01X9160Y-503585D02*
X9630Y-502955D01*
X10178Y-502640D01*
X10805Y-502535D01*
X11588Y-502745D01*
X12136Y-503270D01*
X12293Y-503900D01*
X12215Y-504530D01*
X11901Y-505055D01*
X10335Y-506105D01*
X9630Y-506840D01*
X9160Y-507890D01*
X9003Y-508835D01*
X12293D01*
G01X16948D02*
Y-502535D01*
X16008Y-503795D01*
G01Y-508835D02*
X17888D01*
G01X23248D02*
Y-502535D01*
X22308Y-503795D01*
G01Y-508835D02*
X24188D01*
G01X29391Y-509990D02*
X29705Y-508625D01*
G01X33498Y-502535D02*
X34595Y-508835D01*
X35848Y-502535D01*
X37101Y-508835D01*
X38198Y-502535D01*
G01X43715Y-508835D02*
X40581D01*
Y-502535D01*
X43715D01*
G01X42461Y-505580D02*
X40581D01*
G01X46646Y-508835D02*
Y-502535D01*
X50250Y-508835D01*
Y-502535D01*
G01X53103Y-508835D02*
Y-502535D01*
G01X56393D02*
Y-508835D01*
G01Y-505685D02*
X53103D01*
G01X59325Y-502535D02*
Y-507050D01*
X59638Y-507995D01*
X60265Y-508625D01*
X61048Y-508835D01*
X61831Y-508625D01*
X62458Y-507995D01*
X62771Y-507050D01*
Y-502535D01*
G01X65390Y-508835D02*
X67348Y-502535D01*
X69306Y-508835D01*
G01X68601Y-506630D02*
X66095D01*
G01X78460Y-503585D02*
X78930Y-502955D01*
X79478Y-502640D01*
X80105Y-502535D01*
X80888Y-502745D01*
X81436Y-503270D01*
X81593Y-503900D01*
X81515Y-504530D01*
X81201Y-505055D01*
X79635Y-506105D01*
X78930Y-506840D01*
X78460Y-507890D01*
X78303Y-508835D01*
X81593D01*
G01X84446D02*
Y-502535D01*
X88050Y-508835D01*
Y-502535D01*
G01X90825Y-508835D02*
Y-502535D01*
X92391D01*
X93018Y-502850D01*
X93488Y-503270D01*
X93880Y-503900D01*
X94193Y-504635D01*
X94271Y-505685D01*
X94193Y-506735D01*
X93880Y-507470D01*
X93488Y-508100D01*
X93018Y-508520D01*
X92391Y-508835D01*
X90825D01*
G01X103581D02*
Y-502535D01*
X105540D01*
X106166Y-502850D01*
X106558Y-503270D01*
X106715Y-504110D01*
X106558Y-504950D01*
X106088Y-505475D01*
X105540Y-505790D01*
X103581D01*
G01X105540D02*
X106715Y-508835D01*
G01X109725D02*
Y-502535D01*
X111291D01*
X111918Y-502850D01*
X112388Y-503270D01*
X112780Y-503900D01*
X113093Y-504635D01*
X113171Y-505685D01*
X113093Y-506735D01*
X112780Y-507470D01*
X112388Y-508100D01*
X111918Y-508520D01*
X111291Y-508835D01*
X109725D01*
G01X117748Y-509045D02*
X117591Y-508940D01*
Y-508730D01*
X117748Y-508625D01*
X117905Y-508730D01*
Y-508940D01*
X117748Y-509045D01*
G01X14048Y-498135D02*
X11528Y-497718D01*
X9323Y-496052D01*
X7433Y-493552D01*
X6173Y-490635D01*
X5543Y-487302D01*
Y-483968D01*
X6173Y-480635D01*
X7433Y-477718D01*
X9323Y-475219D01*
X11528Y-473552D01*
X14048Y-473135D01*
X16568Y-473552D01*
X18773Y-475219D01*
X20663Y-477718D01*
X21923Y-480635D01*
X22553Y-483968D01*
Y-487302D01*
X21923Y-490635D01*
X20663Y-493552D01*
X18773Y-496052D01*
X16568Y-497718D01*
X14048Y-498135D01*
G01X16568Y-491468D02*
X20348Y-498135D01*
G01X33893Y-481469D02*
Y-493135D01*
X35153Y-496052D01*
X37043Y-497718D01*
X39248Y-498135D01*
X41453Y-497718D01*
X43343Y-496052D01*
X44603Y-493135D01*
G01Y-498135D02*
Y-481469D01*
G01X70118Y-498135D02*
Y-481469D01*
G01Y-484385D02*
X68858Y-482719D01*
X66968Y-481885D01*
X64763Y-481469D01*
X62558Y-482302D01*
X60668Y-483968D01*
X59408Y-486469D01*
X58778Y-489802D01*
X59408Y-493135D01*
X60668Y-495636D01*
X62558Y-497302D01*
X64763Y-498135D01*
X66968Y-497718D01*
X68858Y-496469D01*
X70118Y-494802D01*
G01X84293Y-498135D02*
Y-481469D01*
G01Y-485635D02*
X85553Y-483552D01*
X87443Y-481885D01*
X89963Y-481469D01*
X92168Y-481885D01*
X94058Y-483552D01*
X95003Y-486469D01*
Y-498135D01*
G01X114848Y-473135D02*
Y-498135D01*
G01X110438Y-481469D02*
X119258D01*
G01X145718Y-498135D02*
Y-481469D01*
G01Y-484385D02*
X144458Y-482719D01*
X142568Y-481885D01*
X140363Y-481469D01*
X138158Y-482302D01*
X136268Y-483968D01*
X135008Y-486469D01*
X134378Y-489802D01*
X135008Y-493135D01*
X136268Y-495636D01*
X138158Y-497302D01*
X140363Y-498135D01*
X142568Y-497718D01*
X144458Y-496469D01*
X145718Y-494802D01*
G01X185398Y-477835D02*
Y-485835D01*
X189398D01*
G01X197198D02*
Y-480502D01*
G01Y-481435D02*
X196798Y-480902D01*
X196198Y-480635D01*
X195498Y-480502D01*
X194798Y-480768D01*
X194198Y-481302D01*
X193798Y-482102D01*
X193598Y-483168D01*
X193798Y-484235D01*
X194198Y-485035D01*
X194798Y-485568D01*
X195498Y-485835D01*
X196198Y-485702D01*
X196798Y-485302D01*
X197198Y-484769D01*
G01X201298Y-488235D02*
X201898Y-488502D01*
X202698Y-488235D01*
X203198Y-487702D01*
X203598Y-487035D01*
X204198Y-484902D01*
X205498Y-480502D01*
G01X202298D02*
X204198Y-484902D01*
G01X209898Y-482235D02*
X213098D01*
X212798Y-481302D01*
X212298Y-480768D01*
X211598Y-480502D01*
X210898Y-480635D01*
X210298Y-481035D01*
X209898Y-481968D01*
X209698Y-482769D01*
Y-483568D01*
X209898Y-484368D01*
X210398Y-485168D01*
X210998Y-485702D01*
X211698Y-485835D01*
X212398Y-485568D01*
X213098Y-484769D01*
G01X217998Y-485835D02*
Y-480502D01*
G01Y-481568D02*
X218498Y-481035D01*
X218998Y-480635D01*
X219698Y-480502D01*
X220198Y-480635D01*
X220798Y-481035D01*
G01X211398Y-535835D02*
Y-532235D01*
X209398Y-527835D01*
G01X213398D02*
X211398Y-532235D01*
G01X217698Y-530502D02*
Y-534235D01*
X218098Y-535168D01*
X218698Y-535702D01*
X219398Y-535835D01*
X220098Y-535702D01*
X220698Y-535168D01*
X221098Y-534235D01*
G01Y-535835D02*
Y-530502D01*
G01X225698Y-535835D02*
Y-530502D01*
G01Y-531835D02*
X226098Y-531168D01*
X226698Y-530635D01*
X227498Y-530502D01*
X228198Y-530635D01*
X228798Y-531168D01*
X229098Y-532102D01*
Y-535835D01*
G01X237198D02*
Y-530502D01*
G01Y-531435D02*
X236798Y-530902D01*
X236198Y-530635D01*
X235498Y-530502D01*
X234798Y-530768D01*
X234198Y-531302D01*
X233798Y-532102D01*
X233598Y-533168D01*
X233798Y-534235D01*
X234198Y-535035D01*
X234798Y-535568D01*
X235498Y-535835D01*
X236198Y-535702D01*
X236798Y-535302D01*
X237198Y-534769D01*
G01X198798Y-510835D02*
Y-502835D01*
X201398Y-509502D01*
X203998Y-502835D01*
Y-510835D01*
G01X206898D02*
X209398Y-502835D01*
X211898Y-510835D01*
G01X210998Y-508035D02*
X207798D01*
G01X215298Y-509769D02*
X216098Y-510435D01*
X216998Y-510835D01*
X217798D01*
X218598Y-510435D01*
X219198Y-509769D01*
X219498Y-508835D01*
X219298Y-507902D01*
X218798Y-507102D01*
X217898Y-506568D01*
X216698Y-506302D01*
X215998Y-505768D01*
X215698Y-504835D01*
X215898Y-503902D01*
X216398Y-503235D01*
X217098Y-502835D01*
X217798D01*
X218498Y-503102D01*
X219098Y-503768D01*
G01X223198Y-510835D02*
Y-502835D01*
G01X226998D02*
X223198Y-507769D01*
G01X227598Y-510835D02*
X224898Y-505502D01*
G01X232098Y-508168D02*
X234698D01*
G01X242198Y-506568D02*
X242598Y-506168D01*
X242898Y-505502D01*
X243098Y-504568D01*
X242898Y-503768D01*
X242498Y-503235D01*
X241798Y-502835D01*
X239098D01*
Y-510835D01*
X242398D01*
X243098Y-510302D01*
X243498Y-509502D01*
X243698Y-508568D01*
X243498Y-507635D01*
X242898Y-506835D01*
X242198Y-506568D01*
X239098D01*
G01X249398Y-510835D02*
X248598Y-510702D01*
X247898Y-510168D01*
X247298Y-509368D01*
X246898Y-508435D01*
X246698Y-507368D01*
Y-506302D01*
X246898Y-505235D01*
X247298Y-504302D01*
X247898Y-503502D01*
X248598Y-502968D01*
X249398Y-502835D01*
X250198Y-502968D01*
X250898Y-503502D01*
X251498Y-504302D01*
X251898Y-505235D01*
X252098Y-506302D01*
Y-507368D01*
X251898Y-508435D01*
X251498Y-509368D01*
X250898Y-510168D01*
X250198Y-510702D01*
X249398Y-510835D01*
G01X257398Y-502835D02*
Y-510835D01*
G01X255098Y-502835D02*
X259698D01*
G01X311998Y-529168D02*
X312598Y-528368D01*
X313298Y-527968D01*
X314098Y-527835D01*
X315098Y-528102D01*
X315798Y-528768D01*
X315998Y-529568D01*
X315898Y-530369D01*
X315498Y-531035D01*
X313498Y-532368D01*
X312598Y-533302D01*
X311998Y-534635D01*
X311798Y-535835D01*
X315998D01*
G01X321898Y-527835D02*
X321098Y-528102D01*
X320498Y-528768D01*
X320098Y-529568D01*
X319798Y-530635D01*
X319698Y-531835D01*
X319798Y-533035D01*
X320098Y-534102D01*
X320498Y-534902D01*
X321098Y-535568D01*
X321898Y-535835D01*
X322698Y-535568D01*
X323298Y-534902D01*
X323698Y-534102D01*
X323998Y-533035D01*
X324098Y-531835D01*
X323998Y-530635D01*
X323698Y-529568D01*
X323298Y-528768D01*
X322698Y-528102D01*
X321898Y-527835D01*
G01X327998Y-529168D02*
X328598Y-528368D01*
X329298Y-527968D01*
X330098Y-527835D01*
X331098Y-528102D01*
X331798Y-528768D01*
X331998Y-529568D01*
X331898Y-530369D01*
X331498Y-531035D01*
X329498Y-532368D01*
X328598Y-533302D01*
X327998Y-534635D01*
X327798Y-535835D01*
X331998D01*
G01X335698Y-534235D02*
X336298Y-535168D01*
X337098Y-535702D01*
X337998Y-535835D01*
X338798Y-535702D01*
X339598Y-535035D01*
X340098Y-534235D01*
X340198Y-533435D01*
X339998Y-532502D01*
X339298Y-531835D01*
X338598Y-531568D01*
X337698D01*
G01X338598D02*
X339198Y-531168D01*
X339698Y-530502D01*
X339898Y-529702D01*
X339698Y-528902D01*
X339198Y-528235D01*
X338298Y-527835D01*
X337398Y-527968D01*
X336498Y-528502D01*
G01X344098Y-536102D02*
X347698Y-527835D01*
G01X353898D02*
X353098Y-528102D01*
X352498Y-528768D01*
X352098Y-529568D01*
X351798Y-530635D01*
X351698Y-531835D01*
X351798Y-533035D01*
X352098Y-534102D01*
X352498Y-534902D01*
X353098Y-535568D01*
X353898Y-535835D01*
X354698Y-535568D01*
X355298Y-534902D01*
X355698Y-534102D01*
X355998Y-533035D01*
X356098Y-531835D01*
X355998Y-530635D01*
X355698Y-529568D01*
X355298Y-528768D01*
X354698Y-528102D01*
X353898Y-527835D01*
G01X361898Y-535835D02*
Y-527835D01*
X360698Y-529435D01*
G01Y-535835D02*
X363098D01*
G01X368098Y-536102D02*
X371698Y-527835D01*
G01X377898D02*
X377098Y-528102D01*
X376498Y-528768D01*
X376098Y-529568D01*
X375798Y-530635D01*
X375698Y-531835D01*
X375798Y-533035D01*
X376098Y-534102D01*
X376498Y-534902D01*
X377098Y-535568D01*
X377898Y-535835D01*
X378698Y-535568D01*
X379298Y-534902D01*
X379698Y-534102D01*
X379998Y-533035D01*
X380098Y-531835D01*
X379998Y-530635D01*
X379698Y-529568D01*
X379298Y-528768D01*
X378698Y-528102D01*
X377898Y-527835D01*
G01X384198Y-534902D02*
X384898Y-535568D01*
X385698Y-535835D01*
X386498Y-535568D01*
X387198Y-534769D01*
X387698Y-533568D01*
X387898Y-532368D01*
Y-530902D01*
X387698Y-529702D01*
X387198Y-528635D01*
X386598Y-528102D01*
X385898Y-527835D01*
X385098Y-528102D01*
X384498Y-528635D01*
X384098Y-529435D01*
X383898Y-530502D01*
X384098Y-531435D01*
X384598Y-532368D01*
X385198Y-532902D01*
X385898Y-533035D01*
X386698Y-532769D01*
X387298Y-532102D01*
X387898Y-530902D01*
G01X311698Y-510835D02*
Y-502835D01*
X313698D01*
X314498Y-503235D01*
X315098Y-503768D01*
X315598Y-504568D01*
X315998Y-505502D01*
X316098Y-506835D01*
X315998Y-508168D01*
X315598Y-509102D01*
X315098Y-509902D01*
X314498Y-510435D01*
X313698Y-510835D01*
X311698D01*
G01X319398D02*
X321898Y-502835D01*
X324398Y-510835D01*
G01X323498Y-508035D02*
X320298D01*
G01X329898Y-502835D02*
X329098Y-503102D01*
X328498Y-503768D01*
X328098Y-504568D01*
X327798Y-505635D01*
X327698Y-506835D01*
X327798Y-508035D01*
X328098Y-509102D01*
X328498Y-509902D01*
X329098Y-510568D01*
X329898Y-510835D01*
X330698Y-510568D01*
X331298Y-509902D01*
X331698Y-509102D01*
X331998Y-508035D01*
X332098Y-506835D01*
X331998Y-505635D01*
X331698Y-504568D01*
X331298Y-503768D01*
X330698Y-503102D01*
X329898Y-502835D01*
G01X335998Y-510835D02*
Y-502835D01*
X339798D01*
G01X338398Y-506702D02*
X335998D01*
G01X345898Y-502835D02*
X345098Y-503102D01*
X344498Y-503768D01*
X344098Y-504568D01*
X343798Y-505635D01*
X343698Y-506835D01*
X343798Y-508035D01*
X344098Y-509102D01*
X344498Y-509902D01*
X345098Y-510568D01*
X345898Y-510835D01*
X346698Y-510568D01*
X347298Y-509902D01*
X347698Y-509102D01*
X347998Y-508035D01*
X348098Y-506835D01*
X347998Y-505635D01*
X347698Y-504568D01*
X347298Y-503768D01*
X346698Y-503102D01*
X345898Y-502835D01*
G01X353898D02*
Y-510835D01*
G01X351598Y-502835D02*
X356198D01*
G01X363898Y-510835D02*
X359898D01*
Y-502835D01*
X363898D01*
G01X362298Y-506702D02*
X359898D01*
G01X370698Y-506568D02*
X371098Y-506168D01*
X371398Y-505502D01*
X371598Y-504568D01*
X371398Y-503768D01*
X370998Y-503235D01*
X370298Y-502835D01*
X367598D01*
Y-510835D01*
X370898D01*
X371598Y-510302D01*
X371998Y-509502D01*
X372198Y-508568D01*
X371998Y-507635D01*
X371398Y-506835D01*
X370698Y-506568D01*
X367598D01*
G01X376698Y-502835D02*
X379098D01*
G01X377898D02*
Y-510835D01*
G01X376698D02*
X379098D01*
G01X383998D02*
Y-502835D01*
X387798D01*
G01X386398Y-506702D02*
X383998D01*
G01X393898Y-502835D02*
X393098Y-503102D01*
X392498Y-503768D01*
X392098Y-504568D01*
X391798Y-505635D01*
X391698Y-506835D01*
X391798Y-508035D01*
X392098Y-509102D01*
X392498Y-509902D01*
X393098Y-510568D01*
X393898Y-510835D01*
X394698Y-510568D01*
X395298Y-509902D01*
X395698Y-509102D01*
X395998Y-508035D01*
X396098Y-506835D01*
X395998Y-505635D01*
X395698Y-504568D01*
X395298Y-503768D01*
X394698Y-503102D01*
X393898Y-502835D01*
G01X329498Y-485835D02*
Y-477835D01*
X333298D01*
G01X331898Y-481702D02*
X329498D01*
G01X339398Y-477835D02*
X338598Y-478102D01*
X337998Y-478768D01*
X337598Y-479568D01*
X337298Y-480635D01*
X337198Y-481835D01*
X337298Y-483035D01*
X337598Y-484102D01*
X337998Y-484902D01*
X338598Y-485568D01*
X339398Y-485835D01*
X340198Y-485568D01*
X340798Y-484902D01*
X341198Y-484102D01*
X341498Y-483035D01*
X341598Y-481835D01*
X341498Y-480635D01*
X341198Y-479568D01*
X340798Y-478768D01*
X340198Y-478102D01*
X339398Y-477835D01*
G01X347398D02*
Y-485835D01*
G01X345098Y-477835D02*
X349698D01*
G01X352398Y-488502D02*
X358398D01*
G01X361898Y-482235D02*
X365098D01*
X364798Y-481302D01*
X364298Y-480768D01*
X363598Y-480502D01*
X362898Y-480635D01*
X362298Y-481035D01*
X361898Y-481968D01*
X361698Y-482769D01*
Y-483568D01*
X361898Y-484368D01*
X362398Y-485168D01*
X362998Y-485702D01*
X363698Y-485835D01*
X364398Y-485568D01*
X365098Y-484769D01*
G01X369898Y-480502D02*
X372898Y-485835D01*
G01Y-480502D02*
X369898Y-485835D01*
G01X377598Y-488502D02*
Y-480502D01*
G01Y-481702D02*
X378098Y-481035D01*
X378598Y-480635D01*
X379398Y-480502D01*
X380098Y-480635D01*
X380798Y-481302D01*
X381098Y-482235D01*
X381198Y-483168D01*
X381098Y-484102D01*
X380798Y-485035D01*
X380198Y-485568D01*
X379398Y-485835D01*
X378698Y-485702D01*
X377998Y-485302D01*
X377598Y-484769D01*
G01X389198Y-485835D02*
Y-480502D01*
G01Y-481435D02*
X388798Y-480902D01*
X388198Y-480635D01*
X387498Y-480502D01*
X386798Y-480768D01*
X386198Y-481302D01*
X385798Y-482102D01*
X385598Y-483168D01*
X385798Y-484235D01*
X386198Y-485035D01*
X386798Y-485568D01*
X387498Y-485835D01*
X388198Y-485702D01*
X388798Y-485302D01*
X389198Y-484769D01*
G01X393698Y-485835D02*
Y-480502D01*
G01Y-481835D02*
X394098Y-481168D01*
X394698Y-480635D01*
X395498Y-480502D01*
X396198Y-480635D01*
X396798Y-481168D01*
X397098Y-482102D01*
Y-485835D01*
G01X405198Y-477835D02*
Y-485835D01*
G01Y-484635D02*
X404798Y-485302D01*
X404198Y-485702D01*
X403498Y-485835D01*
X402698Y-485568D01*
X402098Y-484902D01*
X401698Y-484102D01*
X401598Y-483168D01*
X401698Y-482235D01*
X402098Y-481435D01*
X402698Y-480768D01*
X403498Y-480502D01*
X404198Y-480635D01*
X404698Y-480902D01*
X405198Y-481435D01*
G01X409898Y-482235D02*
X413098D01*
X412798Y-481302D01*
X412298Y-480768D01*
X411598Y-480502D01*
X410898Y-480635D01*
X410298Y-481035D01*
X409898Y-481968D01*
X409698Y-482769D01*
Y-483568D01*
X409898Y-484368D01*
X410398Y-485168D01*
X410998Y-485702D01*
X411698Y-485835D01*
X412398Y-485568D01*
X413098Y-484769D01*
G01X417998Y-485835D02*
Y-480502D01*
G01Y-481568D02*
X418498Y-481035D01*
X418998Y-480635D01*
X419698Y-480502D01*
X420198Y-480635D01*
X420798Y-481035D01*
G01X424398Y-488502D02*
X430398D01*
G01X433598Y-485835D02*
Y-477835D01*
G01Y-481835D02*
X434098Y-481035D01*
X434698Y-480635D01*
X435298Y-480502D01*
X436198Y-480768D01*
X436798Y-481302D01*
X437198Y-482235D01*
Y-483302D01*
X436998Y-484368D01*
X436598Y-485168D01*
X435898Y-485702D01*
X435298Y-485835D01*
X434698Y-485702D01*
X434098Y-485302D01*
X433598Y-484635D01*
G01X445198Y-477835D02*
Y-485835D01*
G01Y-484635D02*
X444798Y-485302D01*
X444198Y-485702D01*
X443498Y-485835D01*
X442698Y-485568D01*
X442098Y-484902D01*
X441698Y-484102D01*
X441598Y-483168D01*
X441698Y-482235D01*
X442098Y-481435D01*
X442698Y-480768D01*
X443498Y-480502D01*
X444198Y-480635D01*
X444698Y-480902D01*
X445198Y-481435D01*
G01X400398Y-538835D02*
Y-530835D01*
X399198Y-532435D01*
G01Y-538835D02*
X401598D01*
G01X406498Y-535502D02*
X407198Y-534568D01*
X407798Y-534035D01*
X408598Y-533768D01*
X409298Y-534035D01*
X409798Y-534568D01*
X410198Y-535368D01*
X410298Y-536302D01*
X410198Y-537102D01*
X409798Y-537902D01*
X409198Y-538568D01*
X408498Y-538835D01*
X407698Y-538568D01*
X406998Y-537769D01*
X406598Y-536568D01*
X406498Y-535235D01*
X406698Y-533502D01*
X406998Y-532568D01*
X407498Y-531635D01*
X408198Y-530968D01*
X408898Y-530835D01*
X409598Y-531102D01*
X410098Y-531768D01*
G01X416398Y-539102D02*
X416198Y-538968D01*
Y-538702D01*
X416398Y-538568D01*
X416598Y-538702D01*
Y-538968D01*
X416398Y-539102D01*
G01X422498Y-535502D02*
X423198Y-534568D01*
X423798Y-534035D01*
X424598Y-533768D01*
X425298Y-534035D01*
X425798Y-534568D01*
X426198Y-535368D01*
X426298Y-536302D01*
X426198Y-537102D01*
X425798Y-537902D01*
X425198Y-538568D01*
X424498Y-538835D01*
X423698Y-538568D01*
X422998Y-537769D01*
X422598Y-536568D01*
X422498Y-535235D01*
X422698Y-533502D01*
X422998Y-532568D01*
X423498Y-531635D01*
X424198Y-530968D01*
X424898Y-530835D01*
X425598Y-531102D01*
X426098Y-531768D01*
G01X445398Y-538835D02*
Y-530835D01*
X444198Y-532435D01*
G01Y-538835D02*
X446598D01*
G01X453198D02*
X453398Y-537102D01*
X453698Y-535635D01*
X454098Y-534302D01*
X454598Y-532835D01*
X455398Y-530835D01*
X451398D01*
G01X461398Y-539102D02*
X461198Y-538968D01*
Y-538702D01*
X461398Y-538568D01*
X461598Y-538702D01*
Y-538968D01*
X461398Y-539102D01*
G01X467498Y-532168D02*
X468098Y-531368D01*
X468798Y-530968D01*
X469598Y-530835D01*
X470598Y-531102D01*
X471298Y-531768D01*
X471498Y-532568D01*
X471398Y-533369D01*
X470998Y-534035D01*
X468998Y-535368D01*
X468098Y-536302D01*
X467498Y-537635D01*
X467298Y-538835D01*
X471498D01*
G01X465498Y-513835D02*
Y-505835D01*
X469298D01*
G01X467898Y-509702D02*
X465498D01*
G54D20*
X18037Y1515478D03*
X21537D03*
X63981Y1215113D03*
X96443Y893358D03*
X156299Y1138393D03*
X160039D03*
X220500Y539484D03*
X221263Y635637D03*
X223952Y1216936D03*
X246695Y636173D03*
X291444Y1187015D03*
X408523Y1330128D03*
X404657Y1330152D03*
X395959Y1358035D03*
X400879Y1403302D03*
X395111Y1493965D03*
X409981Y1536970D03*
X404157D03*
X424016Y331124D03*
X425773Y1268456D03*
X418735Y1285548D03*
X414735D03*
X410152Y1408437D03*
X416357Y1401933D03*
X430959Y331073D03*
X431822Y1125816D03*
X427997Y1125801D03*
X441078Y1266694D03*
X436325D03*
X431661Y1268456D03*
X432485Y1322278D03*
X450591Y1010250D03*
Y1017250D03*
X456377Y1026683D03*
X456472Y1266801D03*
X451377Y1266781D03*
X446246Y1266726D03*
X460377Y1026683D03*
X464385Y1026664D03*
X461677Y1266823D03*
X466975D03*
X472592Y1266791D03*
X489121D03*
X478101D03*
X483503D03*
X505791Y720400D03*
X497357Y1125921D03*
X493532Y1125896D03*
X494901Y1268465D03*
X505728D03*
X500302D03*
X522939Y1268550D03*
X519131Y1268549D03*
X537023Y718226D03*
X528741Y815633D03*
X530453Y1268616D03*
X526725Y1268590D03*
X545741Y801633D03*
X552665Y847802D03*
X553383Y893358D03*
X570241Y806133D03*
Y827633D03*
X562231Y847780D03*
X577501Y819532D03*
X588001D03*
X577501Y826532D03*
X588001D03*
X613386Y1138393D03*
X617126D03*
X677586Y539484D03*
X681039Y1216936D03*
X748531Y1187015D03*
X780631Y1453144D03*
X787631Y1022396D03*
X791686D03*
X801082Y1454050D03*
X801998Y1474050D03*
X829852Y889989D03*
X829995Y923060D03*
X829494Y972691D03*
X835000Y758984D03*
X839000Y765984D03*
X835000Y776984D03*
Y794984D03*
X839000Y783984D03*
X835000Y812984D03*
X839000Y801984D03*
Y819984D03*
X836644Y860996D03*
X840381Y923553D03*
X844381D03*
X833898Y1451902D03*
X880054Y761168D03*
X874851D03*
X880054Y780182D03*
X874851Y780192D03*
X875916Y806374D03*
Y816524D03*
X879286Y911821D03*
X875286D03*
X894449Y603847D03*
X886610Y761167D03*
X885110Y780177D03*
X891916Y816524D03*
X895866Y823474D03*
X883866D03*
X888016D03*
X891916D03*
X883286Y911821D03*
X891286D03*
X887286D03*
X904393Y567685D03*
X908517D03*
X898815D03*
X899916Y806374D03*
X909416Y816524D03*
X899286Y911821D03*
X924143Y357875D03*
X918948Y357804D03*
X913716Y806374D03*
X921790Y816524D03*
X927286Y911821D03*
X923286D03*
X919286D03*
X915286D03*
X935124Y837440D03*
X941987Y857116D03*
X934944Y885045D03*
X931286Y911821D03*
X935286D03*
X952957Y922966D03*
X971648Y1224116D03*
X992000Y786484D03*
X985324Y1361790D03*
X999678Y330891D03*
X1021451Y320388D03*
X1025920Y320312D03*
X1013902Y893314D03*
X1029673Y320388D03*
X1051527Y1445495D03*
X1059448Y1438410D03*
X1074212Y1138393D03*
X1070472D03*
X1134673Y539484D03*
X1138125Y1216936D03*
X1160197Y797394D03*
X1173697D03*
X1187431Y874297D03*
X1183431D03*
X1187431Y881797D03*
X1187151Y926518D03*
Y933518D03*
X1205617Y1187015D03*
X1314604Y1273749D03*
X1326601Y334216D03*
X1333725Y334165D03*
X1319999Y1273749D03*
X1335936D03*
X1325478D03*
X1330582D03*
X1338500Y920984D03*
X1346083Y1125735D03*
X1342218Y1125772D03*
X1346362Y1273749D03*
X1351673D03*
X1341226D03*
X1364500Y819484D03*
X1360000D03*
X1355500D03*
X1364765Y1010250D03*
Y1017250D03*
X1356856Y1273749D03*
X1367828D03*
X1362308D03*
X1382667Y819355D03*
X1378000Y819484D03*
X1369000D03*
X1374500Y920984D03*
X1374551Y1026683D03*
X1370551D03*
X1378559Y1026664D03*
X1380936Y1265839D03*
X1372152Y1273716D03*
X1386122Y1265895D03*
X1391272Y1265861D03*
X1396296Y1265859D03*
X1407954Y1125946D03*
X1411829Y1125923D03*
X1411184Y1268594D03*
X1401428Y1265859D03*
X1415181Y1268594D03*
X1406916D03*
X1419451Y1268538D03*
X1440411Y1268594D03*
X1444381D03*
X1436439Y1268619D03*
X1467556Y893358D03*
X1493500Y942984D03*
X1510500Y928984D03*
X1528357Y974575D03*
X1517424Y975153D03*
X1527559Y1138393D03*
X1535000Y933484D03*
Y954984D03*
X1531299Y1138393D03*
X1591760Y539484D03*
X1595212Y1216936D03*
X1662704Y1187015D03*
X1817766Y1205384D03*
G54D11*
X11011Y79720D03*
X10292Y94236D03*
X12786Y87903D03*
X10131Y115473D03*
X19855Y133000D03*
X15948Y141267D03*
X16909Y153263D03*
X12247Y166341D03*
X17313Y166937D03*
X21909Y153263D03*
X22335Y166721D03*
X18320Y195176D03*
X15139Y201683D03*
X22599Y228646D03*
X18206Y244571D03*
X15586Y249108D03*
X18206Y264571D03*
X8335Y280663D03*
X14807Y282181D03*
X15586Y269108D03*
X15499Y288542D03*
X14197Y1014205D03*
X20346Y1069466D03*
X21200Y1091800D03*
X12599Y1438143D03*
X16304Y1468196D03*
X15889Y1494254D03*
X10089D03*
X26588Y97667D03*
X35442D03*
X35048Y103411D03*
X26565Y177448D03*
X32507Y180517D03*
X32585Y199248D03*
X27340Y230556D03*
X36185Y230117D03*
X31595Y227824D03*
X25549Y256394D03*
X29116Y281129D03*
X37117Y279991D03*
X25549Y276394D03*
X34359Y541135D03*
X34732Y534909D03*
X34425Y546553D03*
X34448Y552726D03*
X36494Y616905D03*
X36306Y622285D03*
X27686Y625311D03*
X36692Y633724D03*
X36575Y627713D03*
X28818Y682139D03*
X30479Y1006509D03*
X36024Y1069703D03*
X31631Y1198651D03*
X29880Y1441702D03*
X25674Y1486291D03*
X45988Y90512D03*
X51026Y242913D03*
X48596Y451419D03*
X49643Y464419D03*
X41643Y464919D03*
X43948Y492108D03*
X44563Y482165D03*
X43804Y500202D03*
X45256Y495993D03*
X40362Y610548D03*
X54192Y633473D03*
X42172Y633716D03*
X49192Y628078D03*
X47179Y633736D03*
X42192Y641817D03*
X47949Y822718D03*
X53549Y843118D03*
X52077Y905295D03*
X42470Y1006738D03*
X47314Y1072228D03*
X41172Y1079064D03*
X55188Y1205179D03*
X51023Y1201416D03*
X48842Y1211109D03*
X53479Y1216256D03*
X39452Y1250932D03*
X64829Y92874D03*
X55871Y99961D03*
X70656Y117775D03*
X69607Y135361D03*
X66780Y169454D03*
X59280D03*
X65189Y223661D03*
X65737Y445603D03*
X57857Y446071D03*
X67670Y464818D03*
X58224Y465004D03*
X63154Y462371D03*
X61330Y544895D03*
X63859Y590801D03*
X63684Y597130D03*
X67684Y605637D03*
X66510Y628242D03*
X58181Y627908D03*
X68598Y859415D03*
X59104Y880162D03*
X63969Y869475D03*
X63930Y874694D03*
X63745Y887763D03*
X71528Y913190D03*
X59962Y910251D03*
X55699Y1072761D03*
X61588Y1074481D03*
X62109Y1084656D03*
Y1079656D03*
Y1091656D03*
X60269Y1198820D03*
X63094Y1207604D03*
X55596Y1210466D03*
X65478Y1541980D03*
X64747Y1555890D03*
X69816Y1592527D03*
X60554Y1612002D03*
X66291Y1633801D03*
X82661Y143740D03*
X80041Y148277D03*
X83272Y157842D03*
X80502Y177616D03*
X81083Y172190D03*
X74939Y188727D03*
X72061Y208695D03*
X71696Y226141D03*
X75438Y265701D03*
X85541Y266114D03*
X80525Y265896D03*
X83014Y281982D03*
X77073Y281716D03*
X83819Y290755D03*
X85812Y558161D03*
X78133Y566597D03*
X87243Y564892D03*
X78733Y578405D03*
X84159Y578986D03*
X83684Y596729D03*
X72515Y596089D03*
X77734Y596782D03*
X78129Y656900D03*
X82648Y670679D03*
X73914Y660107D03*
X84845Y659857D03*
X82562Y680037D03*
X78735Y683426D03*
X74700Y842890D03*
X86061Y874859D03*
X80593Y946082D03*
X87632Y1007522D03*
X87000Y1597855D03*
X74909Y1593009D03*
X71910Y1625009D03*
X78291Y1625743D03*
X83689Y1624736D03*
X91224Y141247D03*
X95711Y143518D03*
X94811Y152373D03*
X103456Y157370D03*
X98826Y172665D03*
X98763Y178560D03*
X98653Y183834D03*
X98943Y200864D03*
X92898Y192490D03*
X98173Y190185D03*
X98966Y207037D03*
X99032Y212455D03*
X88098Y231021D03*
X103841Y228631D03*
X89900Y281307D03*
X95943Y377953D03*
X88875Y840940D03*
X90000Y871389D03*
X103770Y868206D03*
X91278Y892822D03*
X96395Y905405D03*
X103692Y900295D03*
X91387Y905295D03*
X103836Y988813D03*
X95836D03*
X94398Y1006648D03*
X91765Y1018307D03*
X88007Y1013678D03*
X88479Y1023731D03*
X100594Y1035088D03*
X103124Y1165091D03*
X119582Y102249D03*
X118307Y110784D03*
X113307D03*
X117886Y124663D03*
X112864Y124879D03*
X107798Y124283D03*
X119230Y138838D03*
X107540Y192665D03*
X117501Y201683D03*
X107572Y208864D03*
X117948Y249108D03*
X117539Y547918D03*
X120250Y758841D03*
X109591Y796905D03*
X110887Y884000D03*
X111836Y988813D03*
X119836D03*
X110409Y1024094D03*
X108971Y1109564D03*
Y1147364D03*
X109415Y1202103D03*
X118533Y1207737D03*
X112048Y1214372D03*
X107803Y1218169D03*
X128950Y97667D03*
X122867Y125107D03*
X131481Y143762D03*
X125381Y148717D03*
X120682Y195176D03*
X134947Y199248D03*
X129702Y230556D03*
X133957Y227824D03*
X120568Y244571D03*
X127911Y256394D03*
X126131Y359511D03*
X125753Y365856D03*
X122437Y860775D03*
X123387Y892000D03*
X135836Y988813D03*
X127836D03*
X124079Y1021954D03*
X120617Y1029427D03*
X124925Y1102091D03*
X130380Y1105091D03*
X124925Y1114691D03*
Y1127291D03*
X130380Y1117691D03*
X124925Y1139891D03*
X130380Y1130291D03*
X130434Y1144964D03*
X130380Y1155491D03*
X124925Y1152491D03*
X130434Y1170164D03*
X124925Y1165091D03*
Y1177691D03*
X131000Y1180266D03*
X136104Y1214835D03*
X135757Y1221407D03*
X135448Y1229402D03*
Y1234921D03*
X126433Y1230407D03*
X137410Y103411D03*
X137804Y97667D03*
X148600Y90650D03*
X138547Y230117D03*
X148061Y378600D03*
X140431Y546805D03*
X147925Y615600D03*
X149469Y634190D03*
X152658Y645389D03*
X136862Y857244D03*
X151836Y988813D03*
X143836D03*
X142026Y1012354D03*
X136571Y1009354D03*
Y1021954D03*
X142026Y1024954D03*
X144640Y1039439D03*
X150952Y1040115D03*
X139862Y1224472D03*
X167191Y92874D03*
X153912Y90615D03*
X161642Y169454D03*
X167551Y223661D03*
X164496Y309405D03*
X161715Y546062D03*
X159836Y988813D03*
X155836Y997860D03*
X153693Y1051037D03*
X156299Y1143390D03*
X165649Y1159350D03*
Y1151870D03*
X167507Y1146271D03*
X168986Y1170092D03*
X167519Y1164960D03*
X170278Y120467D03*
X185023Y143740D03*
X182403Y148277D03*
X171402Y156497D03*
X169142Y169454D03*
X182864Y177616D03*
X183445Y172190D03*
X177301Y188727D03*
X174423Y208695D03*
X174058Y226141D03*
X177800Y265701D03*
X182887Y265896D03*
X179435Y281716D03*
X178689Y1135036D03*
X169389Y1155610D03*
X182478Y1194917D03*
X193007Y100625D03*
X186026Y97475D03*
X193586Y141247D03*
X198073Y143518D03*
X197173Y152373D03*
X201015Y183834D03*
X201125Y178560D03*
X201188Y172665D03*
X195260Y192490D03*
X200535Y190185D03*
X201305Y200864D03*
X201394Y212455D03*
X201328Y207037D03*
X187903Y266114D03*
X192262Y281307D03*
X185376Y281982D03*
X186181Y290755D03*
X185328Y545528D03*
X198940Y551040D03*
X186184Y1135040D03*
X193700Y1217322D03*
X205848Y60513D03*
X214389Y86012D03*
X210482Y94279D03*
X215669Y110784D03*
X210160Y124283D03*
X215226Y124879D03*
X209902Y196665D03*
X209934Y208864D03*
X214983Y218085D03*
X206203Y228631D03*
X204675Y382109D03*
X215500Y544000D03*
X204674Y551683D03*
X208500Y595500D03*
X203500Y606929D03*
X208000Y604567D03*
X203460Y618400D03*
X203741Y612592D03*
X209158Y610072D03*
X209094Y616317D03*
X212401Y1209842D03*
X216141Y1213582D03*
X204921Y1217322D03*
X212401D03*
X221944Y102249D03*
X231312Y97667D03*
X220669Y110784D03*
X225229Y125107D03*
X220248Y124663D03*
X227743Y148717D03*
X221592Y138838D03*
X223044Y195176D03*
X219863Y201683D03*
X232064Y230556D03*
X227323Y228646D03*
X220310Y249108D03*
X222930Y244571D03*
X233417Y253198D03*
X233258Y359186D03*
X228267Y404718D03*
Y412718D03*
X223500Y568000D03*
X221693Y594982D03*
X220333Y617930D03*
X218458Y608776D03*
X225825Y635684D03*
X232998Y1058763D03*
X230321Y1050045D03*
X224169Y1055975D03*
X225001Y1062847D03*
X224780Y1478149D03*
X217985Y1483055D03*
X225765Y1471985D03*
X233313Y1476699D03*
X221899Y1488800D03*
X218021Y1494724D03*
X222843Y1498442D03*
X233180Y1486442D03*
X233166Y1491454D03*
X226135Y1502442D03*
X230758Y1505046D03*
X226971Y1514578D03*
X227552Y1530675D03*
X232622Y1531104D03*
X226971Y1522578D03*
X219981Y1530797D03*
X223322Y1518578D03*
X222119Y1539941D03*
X227882Y1540816D03*
X233753Y1539752D03*
X239772Y103411D03*
X240166Y97667D03*
X237309Y199248D03*
X240909Y230117D03*
X236319Y227824D03*
X234986Y336161D03*
X236264Y342494D03*
X242396Y499906D03*
X245362Y546712D03*
X246695Y626359D03*
X250102Y656321D03*
X235790Y754332D03*
X248556Y824003D03*
X246311Y819000D03*
X238400Y836900D03*
X250165Y1055787D03*
X240597Y1053324D03*
X234976Y1481676D03*
X243535Y1511473D03*
X245500Y1517033D03*
X237633Y1511909D03*
X244600Y1531700D03*
X240808Y1519942D03*
X235687Y1522578D03*
X237580Y1528604D03*
X245937Y1524237D03*
X239949Y1541327D03*
X244912Y1539389D03*
X250962Y90650D03*
X256274Y90615D03*
X260595Y99961D03*
X264004Y169454D03*
X265011Y403307D03*
X260111Y443585D03*
X252695Y442956D03*
X257999Y433003D03*
X261965Y458455D03*
X262526Y451108D03*
X252542Y507084D03*
X252688Y636364D03*
X256303Y812254D03*
X255289Y824340D03*
X252305Y831018D03*
X265733Y1064608D03*
X250876Y1532782D03*
X255909Y1542043D03*
X250790Y1539759D03*
X275615Y75385D03*
X269553Y92874D03*
X274613Y132920D03*
X271504Y169454D03*
X279663Y188727D03*
X276785Y208695D03*
X276420Y226141D03*
X269913Y223661D03*
X280162Y265701D03*
X281797Y281716D03*
X277575Y395084D03*
X278784Y435158D03*
X278529Y440489D03*
X282230Y458572D03*
X275123Y847874D03*
X279945Y859855D03*
X275400Y894200D03*
X281800Y929400D03*
X290113Y23188D03*
X289631Y28281D03*
X295369Y100625D03*
X288388Y97475D03*
X287385Y143740D03*
X284765Y148277D03*
X285807Y172190D03*
X285226Y177616D03*
X297622Y192490D03*
X290265Y266114D03*
X285249Y265896D03*
X294624Y281307D03*
X287738Y281982D03*
X288543Y290755D03*
X297719Y339559D03*
X291396Y350223D03*
X288500Y388000D03*
X292358Y393858D03*
X298000Y391496D03*
X295699Y382047D03*
X296000Y403500D03*
X298000Y409000D03*
X294000Y398583D03*
X286100Y1128100D03*
X290944Y1142519D03*
X287204Y1149999D03*
X296450Y1178467D03*
X296012Y1185514D03*
X307916Y60529D03*
X312844Y94279D03*
X312522Y124283D03*
X300435Y143518D03*
X299535Y152373D03*
X303377Y183834D03*
X303550Y172665D03*
X303487Y178560D03*
X302897Y190185D03*
X303667Y200864D03*
X312296Y208864D03*
X303756Y212455D03*
X303690Y207037D03*
X308565Y228631D03*
X315079Y314890D03*
X312263Y324518D03*
X299000Y377912D03*
Y386500D03*
X299088Y397912D03*
X309645Y1142519D03*
X308588Y1263349D03*
X322847Y19806D03*
X321840Y14408D03*
X322113Y26187D03*
X316751Y86012D03*
X324306Y102249D03*
X318031Y110784D03*
X323031D03*
X327591Y125107D03*
X322610Y124663D03*
X317588Y124879D03*
X330105Y148717D03*
X323954Y138838D03*
X325406Y195176D03*
X322225Y201683D03*
X329685Y228646D03*
X322672Y249108D03*
X325292Y244571D03*
X318508Y324322D03*
X315944Y332584D03*
X316067Y347937D03*
X321416Y348015D03*
X318500Y356519D03*
X327456Y550065D03*
X331240Y1221062D03*
X331015Y1232283D03*
X320624Y1284448D03*
X325683Y1287953D03*
X333674Y97667D03*
X342134Y103411D03*
X342528Y97667D03*
X336205Y143762D03*
X339671Y199248D03*
X343271Y230117D03*
X338681Y227824D03*
X334426Y230556D03*
X340988Y244297D03*
X332635Y256394D03*
X347058Y399918D03*
X346645Y418996D03*
X346390Y431730D03*
X344500Y746300D03*
X333985Y1017945D03*
X341077Y1018056D03*
X340500Y1147500D03*
X335190Y1173065D03*
X342009Y1176100D03*
X339776Y1187962D03*
X344657Y1195059D03*
X333500Y1202200D03*
X344064Y1203115D03*
X345307Y1221197D03*
X334899Y1224512D03*
X343175Y1237535D03*
X337884Y1233951D03*
X358636Y90615D03*
X353324Y90650D03*
X362957Y99961D03*
X359486Y385123D03*
X349311Y385644D03*
X354486Y385123D03*
X353894Y406060D03*
X353320Y454214D03*
X353663Y449045D03*
X353367Y459330D03*
X358754Y462060D03*
X363100Y750000D03*
X358696Y775504D03*
X358207Y836462D03*
X352545Y1142666D03*
X360877Y1157404D03*
X354420Y1157544D03*
X352931Y1167768D03*
X357950D03*
X357083Y1185205D03*
X361792Y1187310D03*
X348432Y1187215D03*
X348125Y1180175D03*
X359197Y1197626D03*
X360659Y1209789D03*
X362332Y1230265D03*
X355318Y1228760D03*
X359287Y1633665D03*
X353242Y1634202D03*
X379613Y75385D03*
X371915Y92874D03*
X373866Y169454D03*
X366366D03*
X379147Y208695D03*
X372275Y223661D03*
X378782Y226141D03*
X373264Y379429D03*
X378875Y379088D03*
X370486Y373903D03*
X366486Y385123D03*
X370160Y391569D03*
X368587Y409016D03*
X378927Y406739D03*
X367564Y456034D03*
Y461034D03*
X373703Y782555D03*
X365691Y815127D03*
X371507Y815303D03*
X370214Y943812D03*
X379928Y949774D03*
X379245Y956643D03*
X378875Y961862D03*
X378928Y967812D03*
X366429Y1185238D03*
X366222Y1180235D03*
X387948Y27288D03*
X390750Y97475D03*
X385679Y147729D03*
X387588Y177616D03*
X388169Y172190D03*
X382025Y188727D03*
X387611Y265896D03*
X382524Y265701D03*
X392627Y266114D03*
X384159Y281716D03*
X390100Y281982D03*
X390905Y290755D03*
X384173Y379028D03*
X381237Y371076D03*
X394237Y379591D03*
X396373Y407104D03*
X393893Y413611D03*
X393833Y423944D03*
X393646Y474382D03*
X385634Y472020D03*
X385694Y477318D03*
X385293Y466409D03*
X385131Y487382D03*
X381875Y740341D03*
X380331Y782627D03*
X392584Y875845D03*
X384856Y947987D03*
X383710Y1007283D03*
X382465Y1012430D03*
X392234Y1369579D03*
Y1364501D03*
X389466Y1497520D03*
X383259Y1487792D03*
X382896Y1494984D03*
X390449Y1491362D03*
X391740Y1545629D03*
Y1540529D03*
X395296Y1561024D03*
X391740Y1550729D03*
Y1555829D03*
X410789Y22627D03*
X397731Y100625D03*
X405912Y172665D03*
X405739Y183834D03*
X405849Y178560D03*
X399984Y192490D03*
X405259Y190185D03*
X406029Y200864D03*
X406118Y212455D03*
X406052Y207037D03*
X410927Y228631D03*
X396986Y281307D03*
X410086Y336795D03*
X409655Y331589D03*
X410688Y344736D03*
X409994Y351045D03*
X411007Y356743D03*
X405801Y475560D03*
X405301Y467560D03*
X404468Y864407D03*
X406770Y869767D03*
X405466Y881299D03*
X397431Y870654D03*
X401108Y878487D03*
X405179Y959051D03*
X397252Y962861D03*
X396671Y968287D03*
X401063Y1233428D03*
X405063Y1225428D03*
X409063Y1233428D03*
X404324Y1271889D03*
X403798Y1305859D03*
X412663Y1321462D03*
X398456Y1330464D03*
X405294Y1367752D03*
X408773Y1399659D03*
X399373Y1555855D03*
X410034Y1555416D03*
X405496Y1561024D03*
X400396D03*
X410596D03*
X422450Y30483D03*
X414145Y27486D03*
X413904Y32569D03*
X414739Y186778D03*
X414658Y208864D03*
X422988Y323627D03*
X426457Y317115D03*
X426830Y359026D03*
X418435Y351552D03*
X416574Y357528D03*
X421413Y359053D03*
X426647Y452987D03*
X421267Y452799D03*
X414910Y448931D03*
X418801Y474513D03*
X424731Y508152D03*
X427693Y498943D03*
X424993Y728291D03*
X422430Y834800D03*
X425062Y883981D03*
X419987Y1098518D03*
X423340Y1104335D03*
X417063Y1225428D03*
X425063Y1237428D03*
X420830Y1273658D03*
X420922Y1320604D03*
X417305Y1355108D03*
X422875Y1362304D03*
X428084Y1378718D03*
X424376Y1390794D03*
X415421Y1532278D03*
X421454Y1544625D03*
X422539Y1534361D03*
X426701Y1541947D03*
X437386Y143740D03*
X434766Y148277D03*
X436666Y322583D03*
X434927Y317228D03*
X443424Y332988D03*
X440538Y355372D03*
X438098Y442114D03*
X437835Y435101D03*
X432270Y431112D03*
X432440Y440101D03*
X432075Y452718D03*
X438086Y452601D03*
X438078Y447121D03*
X438396Y511493D03*
X443144Y628667D03*
X441162Y638313D03*
X443091Y1026266D03*
X429063Y1225428D03*
X441220Y1271776D03*
X436191Y1271753D03*
X437644Y1296834D03*
X432644D03*
X435705Y1302380D03*
X441153Y1319961D03*
X438549Y1329943D03*
X433318Y1357671D03*
X431127Y1365203D03*
X450436Y143518D03*
X449536Y152373D03*
X446566Y337917D03*
X450852Y372054D03*
X459414Y468689D03*
X459757Y463520D03*
X459461Y473805D03*
X459929Y491669D03*
X460537Y501905D03*
X459952Y496842D03*
X459645Y509486D03*
X447279Y637031D03*
X447921Y630789D03*
X453552Y631779D03*
X460498Y870334D03*
X459360Y996755D03*
Y1012325D03*
X459885Y1018860D03*
X451140Y1021793D03*
X450875Y1028416D03*
X455591Y1015825D03*
X452091Y1039880D03*
X459700Y1032266D03*
X452115Y1098518D03*
X455468Y1104335D03*
X457510Y1224106D03*
X459560Y1239245D03*
X460567Y1230219D03*
X456472Y1271860D03*
X451377Y1271840D03*
X446246Y1271785D03*
X448349Y1314391D03*
X474307Y102249D03*
X474058Y116594D03*
X473032Y110784D03*
X468032D03*
X477592Y125107D03*
X462523Y124283D03*
X467589Y124879D03*
X472611Y124663D03*
X473955Y138838D03*
X475407Y195176D03*
X472226Y201683D03*
X475293Y244571D03*
X472673Y249108D03*
X467335Y359944D03*
X469530Y366754D03*
X473658Y470509D03*
Y475509D03*
X468558Y491669D03*
X468850Y545586D03*
X464776Y636506D03*
X461626Y648827D03*
X474540Y927341D03*
X475018Y992568D03*
X467345Y996480D03*
X464891Y1019069D03*
X473954Y1027202D03*
X464385Y1038534D03*
X471755Y1038665D03*
X470610Y1033783D03*
X475588Y1043055D03*
X470978Y1046591D03*
X469772Y1224717D03*
X469053Y1238094D03*
X467507Y1230974D03*
X461677Y1271882D03*
X467007Y1271914D03*
X472624Y1271807D03*
X463290Y1297035D03*
X492135Y103411D03*
X492529Y97667D03*
X483675D03*
X486206Y143762D03*
X480106Y148717D03*
X489672Y199248D03*
X493272Y230117D03*
X484427Y230556D03*
X488682Y227824D03*
X479686Y228646D03*
X490989Y244297D03*
X482636Y256394D03*
X492817Y357111D03*
X491843Y351089D03*
X490885Y373589D03*
X491053Y365423D03*
X491289Y391589D03*
X490885Y382570D03*
X488438Y418417D03*
X481485Y439900D03*
Y431917D03*
X489485Y431417D03*
X492736Y478982D03*
Y491982D03*
X491818Y534909D03*
X491445Y541135D03*
X482905Y544726D03*
X491534Y552726D03*
X491511Y546553D03*
X493392Y622285D03*
X493580Y616905D03*
X493661Y627713D03*
X493778Y633724D03*
X483059Y662649D03*
X481742Y657477D03*
X482476Y798164D03*
X490706Y859339D03*
X491616Y938771D03*
X479613Y952189D03*
X480711Y999941D03*
X477857Y1004375D03*
X488794Y1024081D03*
X479735Y1032551D03*
X485633Y1036155D03*
X477765Y1093432D03*
X485574Y1098518D03*
X488927Y1104335D03*
X478133Y1271807D03*
X489153Y1271591D03*
X483535Y1271699D03*
X503325Y90650D03*
X508637Y90615D03*
X496023Y362913D03*
X497048Y369450D03*
X495750Y377531D03*
X506500Y379687D03*
X495203Y386890D03*
X503682Y448419D03*
X504729Y469905D03*
X496729Y461919D03*
X504729Y461419D03*
X501224Y492050D03*
X501649Y482165D03*
X500890Y500202D03*
X502493Y495917D03*
X506925Y546830D03*
X497448Y610548D03*
X504265Y633736D03*
X499258Y633716D03*
X506278Y628078D03*
X499278Y641817D03*
X499528Y657843D03*
X496176Y684973D03*
X504508Y783817D03*
X507241Y802149D03*
X495539Y795000D03*
X504641Y789139D03*
X507095Y814784D03*
X507741Y807973D03*
X509665Y824512D03*
X503383Y863025D03*
X498507Y865392D03*
X508248Y873319D03*
X509791Y881932D03*
X509017Y905295D03*
X498435Y1008766D03*
X498524Y997590D03*
X498585Y1016266D03*
X506562Y1238194D03*
X498562Y1226194D03*
Y1242194D03*
X494901Y1273083D03*
X500334Y1273157D03*
X506026Y1273542D03*
X521916Y92874D03*
X512958Y99961D03*
X523867Y169454D03*
X516367D03*
X522276Y223661D03*
X519638Y314346D03*
X512943Y443071D03*
X520823Y442603D03*
X518240Y459371D03*
X512210Y475825D03*
X513310Y462004D03*
X522756Y461818D03*
X513626Y528578D03*
X518416Y544895D03*
X520945Y590801D03*
X520770Y597130D03*
X524770Y605637D03*
X523596Y628242D03*
X515267Y627908D03*
X511278Y633473D03*
X514585Y681325D03*
X520277Y682624D03*
X516973Y713088D03*
X512239Y708434D03*
X511677Y712798D03*
X513504Y755804D03*
X513278Y783286D03*
X526171Y801205D03*
X519891Y795848D03*
X520741Y805149D03*
X524741Y845149D03*
X520870Y874694D03*
X516044Y880162D03*
X520685Y887763D03*
X511025Y911443D03*
X525159Y913818D03*
X516902Y910251D03*
X524475Y952290D03*
X522544Y992854D03*
X512232Y985172D03*
X521055Y1104335D03*
X514562Y1230194D03*
X511876Y1272083D03*
X535984Y79592D03*
X528484D03*
X540751Y97475D03*
X539748Y143740D03*
X537128Y148277D03*
X538170Y172190D03*
X537589Y177616D03*
X532026Y188727D03*
X529148Y208695D03*
X528783Y226141D03*
X532525Y265701D03*
X537612Y265896D03*
X534160Y281716D03*
X540101Y281982D03*
X540906Y290755D03*
X532659Y359557D03*
X526388Y351301D03*
X531612Y354272D03*
X531636Y349057D03*
X528812Y369164D03*
X533211Y364746D03*
X533115Y371856D03*
X530144Y376062D03*
X531953Y380749D03*
X542034Y392209D03*
X541706Y386223D03*
X533189Y390723D03*
X531953Y385749D03*
X535119Y483886D03*
X541572Y556742D03*
X535219Y566797D03*
X535819Y578405D03*
X541245Y578986D03*
X534820Y596782D03*
X540770Y596729D03*
X529601Y596089D03*
X536810Y691203D03*
X536087Y702364D03*
X528653Y708952D03*
X542275Y760782D03*
X539449Y782389D03*
X537578Y772428D03*
X539852Y788099D03*
X530741Y845149D03*
X531076Y913190D03*
X532812Y1273169D03*
X538572Y1289143D03*
X547732Y100625D03*
X552798Y143518D03*
X551898Y152373D03*
X555850Y178560D03*
X555913Y172665D03*
X555740Y183834D03*
X555260Y190185D03*
X549985Y192490D03*
X556030Y200864D03*
X556119Y212455D03*
X556053Y207037D03*
X542628Y266114D03*
X546987Y281307D03*
X551620Y390723D03*
X553563Y384987D03*
X543760Y565997D03*
X547861Y692583D03*
X557751Y750851D03*
X550901Y789509D03*
X544515Y793875D03*
X544741Y809649D03*
X544878Y816309D03*
X556741Y820149D03*
X544741Y823149D03*
X552711Y840120D03*
X557836Y851669D03*
X543001Y874859D03*
X546940Y871389D03*
X547843Y892969D03*
X548327Y905295D03*
X553335Y905405D03*
X552923Y988813D03*
X544719Y1007522D03*
X551485Y1006648D03*
X548852Y1018307D03*
X545094Y1013678D03*
X545566Y1023731D03*
X554696Y1018469D03*
X557681Y1035088D03*
X543621Y1292726D03*
X557584Y1543411D03*
X560573Y60513D03*
X569114Y86012D03*
X565207Y94279D03*
X570394Y110784D03*
X574973Y124663D03*
X564885Y124283D03*
X569951Y124879D03*
X574588Y201683D03*
X564659Y208864D03*
X560928Y228631D03*
X575035Y249108D03*
X573479Y374705D03*
X574625Y547918D03*
X563200Y739600D03*
X571493Y763090D03*
X564362Y757979D03*
X560263Y782207D03*
X567126Y779066D03*
X571984Y784507D03*
X560762Y791422D03*
X564388Y839899D03*
X561134Y869291D03*
X559214Y897425D03*
X567827Y884000D03*
X565003Y936807D03*
X570603Y957207D03*
X560923Y988813D03*
X568923D03*
X567484Y1024003D03*
X566058Y1109564D03*
X560211Y1134764D03*
Y1165091D03*
X566502Y1202103D03*
X575620Y1207737D03*
X569135Y1214372D03*
X564890Y1218169D03*
X570796Y1530309D03*
X563968Y1541445D03*
X568279Y1538438D03*
X572507Y1541375D03*
X576669Y102249D03*
X586037Y97667D03*
X575394Y110784D03*
X579954Y125107D03*
X582468Y148717D03*
X576317Y138838D03*
X577769Y195176D03*
X585016Y198733D03*
X586789Y230556D03*
X591044Y227824D03*
X582048Y228646D03*
X577655Y244571D03*
X584998Y256394D03*
X578193Y336391D03*
X584679Y336285D03*
X577638Y769772D03*
X578271Y763556D03*
X583102Y767137D03*
X587183Y785008D03*
X578204Y775137D03*
X585912Y778470D03*
X588659Y790336D03*
X588501Y811048D03*
X577501Y811548D03*
X582737Y819831D03*
X580327Y892000D03*
X586136Y908935D03*
X586103Y961807D03*
X584923Y988813D03*
X576923D03*
X581166Y1021954D03*
X577704Y1029427D03*
X587880Y1034834D03*
X587467Y1105091D03*
X582012Y1102091D03*
X587467Y1117691D03*
X582012Y1127291D03*
Y1114691D03*
X587467Y1130291D03*
Y1142891D03*
X582012Y1139891D03*
X587467Y1155491D03*
X582012Y1152491D03*
X587467Y1168091D03*
X582012Y1165091D03*
X587467Y1180691D03*
X582012Y1177691D03*
X583520Y1230407D03*
X581803Y1493687D03*
X578859Y1497758D03*
X588859Y1490895D03*
X590826Y1495688D03*
X588507Y1514141D03*
X582027Y1502800D03*
X581803Y1509687D03*
X577931Y1505687D03*
X575809Y1532912D03*
X587809Y1528389D03*
X583809Y1533025D03*
X579809Y1528163D03*
X587809Y1545854D03*
X583809Y1541607D03*
X577571Y1544013D03*
X594497Y103411D03*
X594891Y97667D03*
X605687Y90650D03*
X592034Y199248D03*
X595634Y230117D03*
X593351Y244297D03*
X603554Y250783D03*
X605147Y378600D03*
X602462Y458711D03*
X597517Y546805D03*
X605011Y615600D03*
X604715Y914640D03*
X591754Y956979D03*
X606142Y965665D03*
X597556Y965829D03*
X600923Y988813D03*
X592923D03*
X599113Y1012354D03*
X593658Y1009354D03*
X599113Y1024954D03*
X593658Y1021954D03*
X606434Y1041904D03*
X597026Y1224472D03*
X592991Y1215035D03*
X594183Y1220068D03*
X592885Y1229402D03*
X592634Y1234921D03*
X591487Y1501687D03*
X591481Y1509313D03*
X595809Y1532133D03*
Y1546214D03*
X591809Y1542407D03*
X610999Y90615D03*
X615320Y99961D03*
X618729Y169454D03*
X613401Y242913D03*
X618801Y546062D03*
X616923Y988813D03*
X608923D03*
X612923Y997860D03*
X607993Y1036920D03*
X610780Y1051037D03*
X613386Y1143390D03*
X622736Y1151870D03*
Y1159350D03*
X613738Y1546507D03*
X628153Y81611D03*
X635653D03*
X624278Y92874D03*
X639490Y148277D03*
X626229Y169454D03*
X639951Y177616D03*
X634388Y188727D03*
X631510Y208695D03*
X624638Y223661D03*
X631145Y226141D03*
X639974Y265896D03*
X634887Y265701D03*
X636522Y281716D03*
X632071Y1142487D03*
X624594Y1146271D03*
X626476Y1155610D03*
X626073Y1170092D03*
X624606Y1164960D03*
X639565Y1194917D03*
X650094Y100625D03*
X643113Y97475D03*
X655160Y143518D03*
X642110Y143740D03*
X654260Y152373D03*
X640532Y172190D03*
X652347Y192490D03*
X647547Y231021D03*
X644990Y266114D03*
X649349Y281307D03*
X642463Y281982D03*
X643268Y290755D03*
X642414Y545528D03*
X656026Y551040D03*
X650958Y668153D03*
X643271Y1135040D03*
X650787Y1217322D03*
X662935Y60513D03*
X671476Y86012D03*
X667569Y94279D03*
X658756Y103621D03*
X667247Y124283D03*
X672313Y124879D03*
X658275Y172665D03*
X658212Y178560D03*
X658102Y183834D03*
X657622Y190185D03*
X658392Y200864D03*
X667021Y208864D03*
X658481Y212455D03*
X658415Y207037D03*
X663290Y228631D03*
X661761Y382109D03*
X661760Y551683D03*
X660586Y606929D03*
X665086Y604567D03*
X665586Y595500D03*
X660827Y612592D03*
X666244Y610072D03*
X660546Y618400D03*
X666180Y616317D03*
X665643Y646055D03*
X658064Y650119D03*
X669488Y1209842D03*
X662008Y1217322D03*
X669488D03*
X679031Y102249D03*
X688399Y97667D03*
X677756Y110784D03*
X672756D03*
X682316Y125107D03*
X677335Y124663D03*
X684830Y148717D03*
X678679Y138838D03*
X680131Y195176D03*
X687378Y198733D03*
X676950Y201683D03*
X684410Y228646D03*
X677397Y249108D03*
X680017Y244571D03*
X682857Y339477D03*
X687055Y376456D03*
X685353Y404718D03*
Y412718D03*
X672586Y544000D03*
X680586Y568000D03*
X681256Y1055975D03*
X687408Y1050045D03*
X682088Y1062847D03*
X673228Y1213582D03*
X696859Y103411D03*
X697253Y97667D03*
X690930Y143762D03*
X694396Y199248D03*
X697996Y230117D03*
X689151Y230556D03*
X693406Y227824D03*
X695713Y244297D03*
X690504Y253198D03*
X689486Y339583D03*
X692356Y764614D03*
X691991Y759581D03*
X692155Y778974D03*
X692221Y773449D03*
X697684Y1053324D03*
X690085Y1058763D03*
X701899Y1633858D03*
X708049Y90650D03*
X713361Y90615D03*
X717682Y99961D03*
X721091Y169454D03*
X712692Y356779D03*
X717105Y410964D03*
X717420Y404334D03*
X709781Y442956D03*
X720996Y442856D03*
X715733Y447055D03*
X719051Y458455D03*
X719612Y451108D03*
X706211Y465874D03*
X711463Y546712D03*
X713425Y786029D03*
X707252Y1055787D03*
X707492Y1633514D03*
X713002Y1637887D03*
X729842Y81274D03*
X737342D03*
X726640Y92874D03*
X728591Y169454D03*
X736750Y188727D03*
X733872Y208695D03*
X733507Y226141D03*
X727000Y223661D03*
X737249Y265701D03*
X723404Y379657D03*
X721900Y384500D03*
X723440Y391496D03*
X734661Y393633D03*
X723440Y398583D03*
X728503Y891692D03*
X736452Y890548D03*
X728692Y886653D03*
X725194Y942073D03*
X733798Y950186D03*
X722820Y1064608D03*
X726823Y1263349D03*
X736067Y1611892D03*
X729600Y1625165D03*
X732268Y1618260D03*
X752456Y100625D03*
X745475Y97475D03*
X744472Y143740D03*
X741852Y148277D03*
X742894Y172190D03*
X742313Y177616D03*
X747352Y266114D03*
X742336Y265896D03*
X751711Y281307D03*
X744825Y281982D03*
X738884Y281716D03*
X745630Y290755D03*
X749444Y393858D03*
X745586Y388000D03*
X752785Y382047D03*
X753086Y403500D03*
X751086Y398583D03*
X739316Y458572D03*
X744069Y746617D03*
X742000Y768137D03*
X738707Y987952D03*
X745673Y1007009D03*
X743200Y1128100D03*
X748031Y1142519D03*
X744291Y1149999D03*
X753099Y1185514D03*
X753537Y1178467D03*
X749786Y1590517D03*
X738775Y1597866D03*
X749704Y1608631D03*
X765297Y60513D03*
X769931Y94279D03*
X769609Y124283D03*
X757522Y143518D03*
X756622Y152373D03*
X760637Y172665D03*
X760464Y183834D03*
X760574Y178560D03*
X754709Y192490D03*
X759984Y190185D03*
X760754Y200864D03*
X769383Y208864D03*
X760843Y212455D03*
X760777Y207037D03*
X769349Y324518D03*
X754805Y339559D03*
X759624Y353961D03*
X756086Y377912D03*
X755086Y391496D03*
X756086Y386500D03*
X756174Y397912D03*
X755086Y409000D03*
X767585Y433666D03*
X765105Y572830D03*
Y600537D03*
X757721Y617468D03*
X755512Y1112598D03*
X766732Y1142519D03*
X760398Y1440276D03*
X763542Y1590186D03*
X767310Y1599164D03*
X768361Y1610083D03*
X756358Y1616917D03*
X773838Y86012D03*
X781393Y102249D03*
X775118Y110784D03*
X780118D03*
X784678Y125107D03*
X779697Y124663D03*
X774675Y124879D03*
X781041Y138838D03*
X782493Y195176D03*
X779312Y201683D03*
X774432Y218085D03*
X782379Y244571D03*
X779759Y249108D03*
X772165Y314890D03*
X784118Y303962D03*
X772162Y332584D03*
X778502Y348015D03*
X772859Y347937D03*
X784902Y428653D03*
X780782Y433440D03*
X783620Y1460108D03*
X781110Y1595254D03*
X777059Y1608982D03*
X784046Y1600438D03*
X799221Y103411D03*
X799615Y97667D03*
X790761D03*
X793292Y143762D03*
X787192Y148717D03*
X796758Y199248D03*
X789740Y198733D03*
X800358Y230117D03*
X795768Y227824D03*
X791513Y230556D03*
X786772Y228646D03*
X798075Y244297D03*
X789722Y256394D03*
X786461Y293028D03*
X790280Y287421D03*
X795445Y356950D03*
X789581Y405011D03*
X793893Y409502D03*
X802136Y448334D03*
X794733Y915483D03*
X797178Y922746D03*
X800018Y934000D03*
X792575Y932815D03*
X793810Y1013122D03*
X801043Y1010773D03*
X796338Y1138130D03*
X797160Y1146609D03*
X792277Y1173065D03*
X799020Y1175975D03*
X792382Y1191664D03*
X788208Y1208014D03*
X796777Y1206299D03*
X790587Y1202200D03*
X790749Y1196138D03*
X791986Y1224512D03*
X788327Y1221062D03*
X802394Y1221197D03*
X794971Y1233951D03*
X800262Y1237535D03*
X788102Y1232283D03*
X793548Y1397690D03*
X799330Y1416760D03*
X789647Y1427518D03*
X798601Y1431673D03*
X793288Y1450918D03*
X787694Y1442749D03*
X800607Y1440760D03*
X793994Y1441499D03*
X797083Y1467883D03*
X794005Y1464178D03*
X786591Y1452803D03*
X810411Y90650D03*
X815723Y90615D03*
X817456Y305368D03*
Y313368D03*
X809490Y305368D03*
X809466Y310604D03*
X817100Y319600D03*
X809457Y330459D03*
X809490Y325368D03*
Y317368D03*
X810749Y443045D03*
X810453Y453330D03*
X810406Y448214D03*
X813678Y740979D03*
X817584Y764219D03*
X818000Y797000D03*
X817845Y817879D03*
X818500Y810135D03*
X815863Y830097D03*
X814299Y840877D03*
X813887Y835146D03*
X816037Y845578D03*
X817884Y915425D03*
X806168Y910166D03*
X803507Y926197D03*
X817229Y935344D03*
X818070Y972723D03*
X809632Y1142666D03*
X817964Y1157404D03*
X811507Y1157544D03*
X810018Y1167768D03*
X815037D03*
X814170Y1185205D03*
X805212Y1180175D03*
X805519Y1187215D03*
X816284Y1197626D03*
X804458Y1193112D03*
X817446Y1210089D03*
X812405Y1228760D03*
X806148Y1383715D03*
Y1375208D03*
X810204Y1401661D03*
X804654Y1404769D03*
X805569Y1441519D03*
X802684Y1465549D03*
X807576Y1469584D03*
X834559Y80265D03*
X829002Y92874D03*
X820044Y99961D03*
X823453Y169454D03*
X830953D03*
X829362Y223661D03*
X822160Y258880D03*
X822477Y309368D03*
X829485Y345101D03*
X822626Y348066D03*
X818840Y444091D03*
X824650Y455034D03*
Y450034D03*
X832284Y731216D03*
X821582Y727140D03*
X830484Y738750D03*
X830075Y769000D03*
X824500Y756000D03*
Y774000D03*
Y782500D03*
X830075Y787000D03*
X824342Y792315D03*
X824500Y800500D03*
X830075Y805000D03*
Y823000D03*
X829757Y842672D03*
X822916Y852576D03*
X823540Y857956D03*
X831654Y864494D03*
X822938Y863298D03*
X828835Y854920D03*
X833194Y873561D03*
X827992Y874107D03*
X830063Y898500D03*
X819918Y889365D03*
X824804Y898395D03*
X829848Y914211D03*
X825336Y916774D03*
X834751Y922368D03*
X833683Y936743D03*
X824414Y939655D03*
X822829Y960614D03*
X832432Y977982D03*
X829517Y1010303D03*
X823549Y1009583D03*
X825744Y1146937D03*
X818879Y1187310D03*
X823309Y1180235D03*
X823516Y1185238D03*
X819419Y1230265D03*
X826204Y1440689D03*
X826341Y1451236D03*
X826365Y1458974D03*
X842059Y80265D03*
X847837Y97475D03*
X844675Y177616D03*
X845256Y172190D03*
X839112Y188727D03*
X836234Y208695D03*
X835869Y226141D03*
X844698Y265896D03*
X839611Y265701D03*
X849714Y266114D03*
X841246Y281716D03*
X847187Y281982D03*
X847992Y290755D03*
X845435Y356172D03*
X849591Y411388D03*
X842515Y461382D03*
X850732Y469382D03*
X842779Y473076D03*
X842916Y467009D03*
X848444Y657756D03*
X837272Y663910D03*
X842352Y659243D03*
X845850Y710969D03*
X836078Y709619D03*
X848284Y731181D03*
X846484Y738750D03*
X836713Y738751D03*
X844520Y791925D03*
X835215Y847719D03*
X835346Y891346D03*
X843665Y907110D03*
X841689Y941243D03*
X842856Y949146D03*
X843734Y1008778D03*
X843650Y1449546D03*
X835474Y1457397D03*
X854818Y100625D03*
X862826Y183834D03*
X862999Y172665D03*
X862936Y178560D03*
X857071Y192490D03*
X862346Y190185D03*
X863116Y200864D03*
X863205Y212455D03*
X863139Y207037D03*
X852271Y231021D03*
X866015Y224536D03*
X854073Y281307D03*
X863430Y309368D03*
Y316970D03*
X863114Y324505D03*
X863040Y330140D03*
X860586Y383000D03*
X861235Y394000D03*
X854086Y392999D03*
X855017Y411969D03*
X867093Y570703D03*
Y582828D03*
X861663Y646653D03*
X855300Y646819D03*
X853982Y657506D03*
X859441Y678015D03*
X864029Y688970D03*
X858186Y713170D03*
X867455Y710611D03*
X858002Y707244D03*
X867227Y722060D03*
X859199Y744517D03*
X854484Y738633D03*
X859000Y756000D03*
X854758Y766075D03*
X852710Y755925D03*
X859000Y774000D03*
X853837Y784075D03*
X851584Y773925D03*
X859000Y792000D03*
X853837Y802075D03*
X859000Y810000D03*
X853851Y818000D03*
X852250Y809925D03*
X856992Y829054D03*
X863206Y864154D03*
X865218Y853311D03*
X867310Y873743D03*
X861771Y874368D03*
X863631Y883459D03*
X862868Y891471D03*
X858988Y898307D03*
X867096Y935963D03*
X858601Y934505D03*
X853030Y934690D03*
X851925Y951350D03*
X860887Y1023208D03*
X867659Y60513D03*
X876200Y86012D03*
X867787Y85731D03*
X872293Y94279D03*
X872816Y244389D03*
X883118Y262687D03*
X873262Y300030D03*
X869924Y305368D03*
Y313368D03*
Y321368D03*
Y328722D03*
X874005Y344917D03*
X870413Y342791D03*
X869924Y333722D03*
X877909Y391731D03*
X882925Y391099D03*
X872736Y391754D03*
X867586Y393000D03*
X868586Y398500D03*
X874253Y420080D03*
X869454Y479303D03*
X869954Y487303D03*
X882954Y486256D03*
X882195Y539204D03*
X872264Y558530D03*
X883525Y554619D03*
X878382Y554942D03*
X876949Y571419D03*
X872264Y566530D03*
Y562530D03*
X881476Y588202D03*
X881131Y577349D03*
X877400Y584126D03*
X875290Y578703D03*
X878881Y667156D03*
X880501Y710611D03*
X873021Y715729D03*
X879875Y753612D03*
X873728Y752692D03*
X874851Y769017D03*
X880054Y769358D03*
X870017Y757313D03*
X874807Y784757D03*
X870000Y780000D03*
X879887Y784719D03*
X880040Y792851D03*
X881753Y833087D03*
X869886Y846907D03*
X869609Y841429D03*
X880404Y839742D03*
X875820Y843856D03*
X875171Y850086D03*
X870108Y862191D03*
X876751Y865038D03*
X878246Y859995D03*
X873845Y855576D03*
X870300Y881119D03*
X871876Y869076D03*
X873432Y874571D03*
X879286Y895183D03*
X877080Y887376D03*
X868945Y887459D03*
X871600Y898584D03*
X883286Y901937D03*
X876481Y941126D03*
X872126Y934766D03*
X870209Y949384D03*
X869741Y1025895D03*
X869902Y1079077D03*
X875600Y1096200D03*
X875321Y1207654D03*
X883142Y1259935D03*
X878244Y1451605D03*
X879174Y1459551D03*
X894472Y143740D03*
X891852Y148277D03*
X895064Y250186D03*
X885884Y255118D03*
X897004Y257480D03*
X892484Y260860D03*
X886496Y268968D03*
X886059Y284644D03*
X885953Y321368D03*
Y333368D03*
X888812Y357372D03*
X890553Y392038D03*
X889219Y426952D03*
X891699Y420445D03*
X885556Y543664D03*
X890274Y565040D03*
X894274D03*
X895933Y609696D03*
X886836Y729778D03*
X886610Y769419D03*
X890722Y777118D03*
X884894Y784778D03*
X892040Y784511D03*
X898737Y792289D03*
X889516Y792851D03*
X886065Y828112D03*
X890254Y835978D03*
X891386Y899501D03*
X887286Y896235D03*
X897623Y902409D03*
X891367Y941126D03*
X885099Y1021685D03*
X887862Y1088067D03*
X894004Y1081231D03*
X889033Y1134078D03*
X889967Y1147844D03*
X888650Y1199622D03*
X894713Y1210419D03*
X898878Y1214182D03*
X899286Y1219469D03*
X892532Y1220112D03*
X897169Y1225259D03*
X889244Y1444859D03*
X907522Y143518D03*
X906622Y152373D03*
X915653Y307438D03*
X905483Y355262D03*
X905000Y362158D03*
X906161Y367191D03*
X910646Y376084D03*
X906344Y372524D03*
X910236Y465272D03*
X914296Y558143D03*
X913728Y550495D03*
X908846Y560124D03*
X910789Y598726D03*
X912462Y683770D03*
Y695770D03*
X913247Y714204D03*
X909038Y806465D03*
X914577Y827133D03*
X902630Y828027D03*
X915095Y838701D03*
X911286Y899612D03*
X911487Y894491D03*
X914199Y890063D03*
X906586Y900841D03*
X900983Y940895D03*
X906909Y951494D03*
X909811Y962400D03*
X902389Y1081764D03*
X908799Y1093659D03*
Y1088659D03*
X908278Y1083484D03*
X908799Y1100659D03*
X902353Y1104333D03*
X903959Y1207823D03*
X906784Y1216607D03*
X931393Y102249D03*
X930118Y110784D03*
X925118D03*
X924675Y124879D03*
X929697Y124663D03*
X919609Y124283D03*
X931041Y138838D03*
X929978Y186854D03*
X923732Y304585D03*
X923311Y349959D03*
X921343Y376888D03*
X916330Y377748D03*
X929947Y376821D03*
X927766Y456442D03*
X927596Y447453D03*
X921973Y469328D03*
X927401Y469059D03*
X916593Y469140D03*
X917811Y544325D03*
X921306Y567295D03*
X927288Y567117D03*
X923642Y561578D03*
X923599Y581578D03*
X920165Y594914D03*
X930450Y603319D03*
X929790Y828603D03*
X921127Y833588D03*
X927867Y823081D03*
X921916Y822095D03*
X919702Y826833D03*
X930884Y848974D03*
X925072Y842031D03*
X930626Y842386D03*
X931145Y865672D03*
X931826Y874531D03*
X922475Y894575D03*
X917770Y897618D03*
X923892Y889077D03*
X929181Y895029D03*
X931597Y900701D03*
X916628Y918042D03*
X928628D03*
X929741Y967006D03*
X924956Y994321D03*
X924864Y1023208D03*
X916749Y1092664D03*
X930754Y1310564D03*
X925909Y1413070D03*
X940761Y97667D03*
X934678Y125107D03*
X943292Y143762D03*
X937192Y148717D03*
X933159Y180347D03*
X947424Y184419D03*
X940406Y183904D03*
X946234Y213390D03*
X942179Y215727D03*
X937438Y213817D03*
X936962Y249807D03*
X944248Y239844D03*
X934128Y355168D03*
X944238Y360828D03*
X936175Y364823D03*
X933424Y458455D03*
X933161Y451442D03*
X933404Y463462D03*
X933412Y468942D03*
X948532Y541135D03*
X939992Y544726D03*
X948598Y546553D03*
X948621Y552726D03*
X935281Y677795D03*
X939314Y707847D03*
X933201Y798297D03*
X946970Y786366D03*
X938357Y808856D03*
X940100Y830700D03*
X933344Y821858D03*
X943382Y835395D03*
X933713Y860799D03*
X937333Y864332D03*
X942194Y891216D03*
X944628Y928101D03*
X933810Y972433D03*
X945671Y982191D03*
X943093Y1021769D03*
X948633Y1078908D03*
X933879Y1079077D03*
X939298Y1207654D03*
X947119Y1259935D03*
X944207Y1320739D03*
X947308Y1325035D03*
X944235Y1406262D03*
X947411Y1443901D03*
X934456Y1479446D03*
X937671Y1492139D03*
X949221Y103411D03*
X949615Y97667D03*
X960411Y90650D03*
X950177Y215730D03*
X948741Y229468D03*
X948785Y242464D03*
X950953Y317947D03*
X962769Y451419D03*
X955816Y464919D03*
X963816Y464419D03*
X958124Y492354D03*
X958736Y482165D03*
X959600Y496486D03*
X957977Y500202D03*
X948905Y534909D03*
X950479Y622285D03*
X954535Y610548D03*
X950667Y616905D03*
X963365Y628078D03*
X961352Y633736D03*
X950865Y633724D03*
X950748Y627713D03*
X956345Y633716D03*
X956365Y641817D03*
X956023Y706907D03*
X963869Y725057D03*
X955950Y734178D03*
X957763Y725336D03*
X957579Y744168D03*
X953837Y763025D03*
X950699Y779711D03*
X949609Y796051D03*
X957487Y798553D03*
X955343Y866850D03*
X964280Y927777D03*
X958567Y927654D03*
X951863Y936168D03*
X957235Y936398D03*
X962329Y936229D03*
X957671Y977921D03*
X949671D03*
X957671Y991564D03*
X953671Y982191D03*
X954937Y1021998D03*
X957981Y1081231D03*
X951839Y1088067D03*
X953010Y1134078D03*
X953944Y1147844D03*
X952627Y1199622D03*
X958690Y1210419D03*
X963263Y1219469D03*
X962855Y1214182D03*
X956509Y1220112D03*
X961146Y1225259D03*
X952395Y1395276D03*
X958585Y1389437D03*
X952035Y1401223D03*
X957947Y1484672D03*
X979002Y92874D03*
X965723Y90615D03*
X970044Y99961D03*
X980953Y169454D03*
X973453D03*
X979362Y223661D03*
X975631Y343112D03*
X972030Y446071D03*
X979910Y445603D03*
X972397Y465004D03*
X977327Y462371D03*
X975868Y527449D03*
X978303Y544895D03*
X978032Y590801D03*
X977857Y597130D03*
X980683Y628242D03*
X972354Y627908D03*
X968365Y633473D03*
X973450Y747280D03*
X974437Y849140D03*
X973510Y834991D03*
X967842Y864801D03*
X970299Y853773D03*
X978880Y869552D03*
X973130Y880162D03*
X977771Y887684D03*
X966813Y904556D03*
X973988Y910038D03*
X965671Y982191D03*
X966366Y1081764D03*
X972776Y1093659D03*
X972255Y1083484D03*
X972776Y1088659D03*
X966330Y1104333D03*
X972776Y1100659D03*
X967936Y1207823D03*
X970761Y1216607D03*
X974985Y1290950D03*
X979996Y1386100D03*
X974882Y1392080D03*
X973806Y1444392D03*
X993743Y78919D03*
X986243D03*
X996834Y143740D03*
X994214Y148277D03*
X995256Y172190D03*
X994675Y177616D03*
X989112Y188727D03*
X986234Y208695D03*
X985869Y226141D03*
X989611Y265701D03*
X994698Y265896D03*
X991246Y281716D03*
X997187Y281982D03*
X987517Y314092D03*
X993552Y318175D03*
X989630Y343862D03*
X983717Y341665D03*
X983956Y346652D03*
X993026Y353813D03*
X981719Y352217D03*
X997059Y348522D03*
X988631Y349496D03*
X989950Y360307D03*
X986373Y370467D03*
X981843Y464818D03*
X992206Y483886D03*
X985699Y480705D03*
X985334Y498151D03*
X982375Y529929D03*
X986268Y532949D03*
X992306Y566797D03*
X992906Y578405D03*
X991907Y596782D03*
X986688Y596089D03*
X986600Y717641D03*
X987461Y745796D03*
X985921Y805135D03*
X994094Y829000D03*
X987702Y829159D03*
X987703Y837159D03*
X992441Y870398D03*
X985554Y913434D03*
X986177Y1367678D03*
X983400Y1381496D03*
X984600Y1386800D03*
X985448Y1398271D03*
X994994Y1444240D03*
X982241Y1489637D03*
X1004818Y100625D03*
X997837Y97475D03*
X1013480Y103621D03*
X1005397Y141247D03*
X1009884Y143518D03*
X1008984Y152373D03*
X1012936Y178560D03*
X1012826Y183834D03*
X1012999Y172665D03*
X1012346Y190185D03*
X1007071Y192490D03*
X1013116Y200864D03*
X1013139Y207037D03*
X1013205Y212455D03*
X999714Y266114D03*
X1004061Y280808D03*
X997992Y290755D03*
X1002580Y309619D03*
X1003181Y323057D03*
X1001105Y318006D03*
X1000411Y555306D03*
X1001926Y565908D03*
X998332Y578986D03*
X997857Y596729D03*
X1013151Y756726D03*
X1013319Y785929D03*
X1006053Y787745D03*
X1012703Y837659D03*
X1001187Y850084D03*
X1002176Y875303D03*
X1005413Y892787D03*
Y905295D03*
X1006619Y933822D03*
X1012219Y954222D03*
X1009564Y988874D03*
X1001805Y1007522D03*
X1008571Y1006648D03*
X1002180Y1013678D03*
X1002652Y1023731D03*
X1005938Y1018307D03*
X998600Y1369200D03*
X999283Y1377400D03*
X998643Y1398271D03*
X998685Y1389915D03*
X1017659Y60513D03*
X1026200Y86012D03*
X1017787Y85731D03*
X1022293Y94279D03*
X1027480Y110784D03*
X1021971Y124283D03*
X1027037Y124879D03*
X1021826Y186778D03*
X1018014Y228631D03*
X1015281Y309620D03*
X1014406Y344620D03*
X1020406Y350772D03*
X1025905Y353890D03*
X1021885Y698974D03*
X1021221Y848712D03*
X1017800Y867065D03*
X1021408Y895008D03*
X1024913Y884000D03*
X1013897Y904950D03*
X1022346Y917669D03*
X1029570Y917718D03*
X1027719Y958822D03*
X1018009Y988813D03*
X1026009D03*
X1024570Y1024003D03*
X1014767Y1035088D03*
X1025143Y1030672D03*
X1023144Y1109564D03*
X1023139Y1184856D03*
X1022420Y1203204D03*
X1026221Y1214372D03*
X1021976Y1218169D03*
X1019391Y1377061D03*
X1020196Y1444492D03*
X1016769Y1489832D03*
X1033755Y102249D03*
X1043123Y97667D03*
X1032480Y110784D03*
X1037040Y125107D03*
X1032059Y124663D03*
X1045654Y143762D03*
X1039554Y148717D03*
X1033403Y138838D03*
X1034855Y195176D03*
X1042102Y198733D03*
X1031674Y201683D03*
X1043875Y230556D03*
X1039134Y228646D03*
X1034741Y244571D03*
X1032121Y249108D03*
X1042084Y256394D03*
X1045650Y300093D03*
X1041783Y321114D03*
X1031259Y350427D03*
X1031712Y547918D03*
X1043016Y782161D03*
X1043425Y830800D03*
X1043626Y836563D03*
X1037527Y836486D03*
X1031813Y850273D03*
X1046045Y841217D03*
X1040822Y841339D03*
X1044390Y861210D03*
X1038363Y875288D03*
X1038010Y902565D03*
X1042009Y988813D03*
X1034009D03*
X1038252Y1021954D03*
X1044553Y1105091D03*
X1039098Y1102091D03*
X1044553Y1117691D03*
X1039098Y1114691D03*
Y1127291D03*
X1044553Y1130291D03*
Y1142891D03*
X1039098Y1139891D03*
X1044553Y1155491D03*
X1039098Y1152491D03*
X1044553Y1168091D03*
X1039098Y1165091D03*
X1044553Y1180691D03*
X1039098Y1177691D03*
X1032831Y1207950D03*
X1040606Y1230407D03*
X1045218Y1444596D03*
X1051583Y103411D03*
X1051977Y97667D03*
X1049120Y199248D03*
X1052720Y230117D03*
X1048130Y227824D03*
X1061387Y343509D03*
X1060679Y356151D03*
X1059549Y458711D03*
X1054604Y546805D03*
X1062098Y615600D03*
X1048314Y833102D03*
X1053392Y832788D03*
X1051550Y823146D03*
X1050358Y837793D03*
X1052500Y841200D03*
X1049087Y856033D03*
X1053909Y855472D03*
X1050009Y988813D03*
X1058009D03*
X1056199Y1012354D03*
X1050744Y1009354D03*
X1056199Y1024954D03*
X1050744Y1021954D03*
X1057212Y1040356D03*
X1049930Y1221407D03*
X1050178Y1214934D03*
X1054295Y1224472D03*
X1049770Y1229402D03*
X1049720Y1234921D03*
X1050944Y1437997D03*
X1062773Y90650D03*
X1068085Y90615D03*
X1072406Y99961D03*
X1075815Y169454D03*
X1076571Y310574D03*
X1075888Y546062D03*
X1063642Y634190D03*
X1066931Y645389D03*
X1065823Y988773D03*
X1074009Y988813D03*
X1070009Y997860D03*
X1065079Y1036920D03*
X1076577Y1041332D03*
X1067866Y1051037D03*
X1070472Y1143390D03*
X1069642Y1445541D03*
X1068861Y1451311D03*
X1085912Y78918D03*
X1093412D03*
X1081364Y92874D03*
X1083315Y169454D03*
X1091474Y188727D03*
X1088596Y208695D03*
X1088231Y226141D03*
X1081724Y223661D03*
X1091973Y265701D03*
X1093608Y281716D03*
X1092554Y340318D03*
X1089145Y1142518D03*
X1081680Y1146271D03*
X1079822Y1151870D03*
X1083562Y1155610D03*
X1079822Y1159350D03*
X1083159Y1170092D03*
X1081692Y1164960D03*
X1084000Y1529600D03*
X1091529Y1528718D03*
X1091525Y1546300D03*
X1091569Y1561300D03*
X1092527Y1579422D03*
X1090469Y1588435D03*
X1083900Y1593206D03*
X1088021Y1606949D03*
X1093778Y1599574D03*
X1086904Y1599004D03*
X1090093Y1628297D03*
X1089474Y1638213D03*
X1100199Y97475D03*
X1107180Y100625D03*
X1107759Y141247D03*
X1099196Y143740D03*
X1096576Y148277D03*
X1097618Y172190D03*
X1109903Y171523D03*
X1097037Y177616D03*
X1109433Y192490D03*
X1102076Y266114D03*
X1097060Y265896D03*
X1106435Y281307D03*
X1099549Y281982D03*
X1100354Y290755D03*
X1105012Y353504D03*
X1099501Y545528D03*
X1104448Y653161D03*
X1108045Y668153D03*
X1100357Y1135040D03*
X1096651Y1194917D03*
X1107873Y1217322D03*
X1107200Y1438914D03*
X1096780Y1526700D03*
X1101402Y1518200D03*
Y1531702D03*
X1098617Y1546183D03*
X1096780Y1535400D03*
X1099371Y1561153D03*
X1100476Y1579318D03*
X1102904Y1566668D03*
X1100233Y1588000D03*
X1098904Y1602138D03*
X1101946Y1614709D03*
X1096941Y1627905D03*
X1105474Y1629450D03*
Y1638426D03*
X1097474Y1637753D03*
X1120021Y60513D03*
X1120149Y85731D03*
X1124655Y94279D03*
X1115842Y103621D03*
X1124333Y124283D03*
X1112246Y143518D03*
X1111346Y152373D03*
X1115188Y183834D03*
X1115298Y178560D03*
X1115361Y172665D03*
X1124075Y192665D03*
X1115478Y200864D03*
X1115501Y207037D03*
X1115567Y212455D03*
X1124107Y208864D03*
X1120376Y228631D03*
X1118848Y382109D03*
X1118847Y551683D03*
X1113113Y551040D03*
X1117673Y606929D03*
X1122673Y595500D03*
X1122173Y604567D03*
X1123331Y610072D03*
X1123267Y616317D03*
X1117633Y618400D03*
X1117914Y612592D03*
X1115151Y650119D03*
X1119094Y1217322D03*
X1126574D03*
Y1209842D03*
X1128562Y86012D03*
X1136117Y102249D03*
X1129842Y110784D03*
X1134842D03*
X1139402Y125107D03*
X1129399Y124879D03*
X1134421Y124663D03*
X1141916Y148717D03*
X1135765Y138838D03*
X1137217Y195176D03*
X1134036Y201683D03*
X1141496Y228646D03*
X1137103Y244571D03*
X1134483Y249108D03*
X1137830Y336230D03*
X1142440Y404718D03*
Y412718D03*
X1135548Y455804D03*
X1129673Y544000D03*
X1137673Y568000D03*
X1138342Y1055975D03*
X1139174Y1062847D03*
X1130314Y1213582D03*
X1153945Y103411D03*
X1145485Y97667D03*
X1154339D03*
X1148016Y143762D03*
X1151482Y199248D03*
X1144464Y198733D03*
X1146237Y230556D03*
X1155082Y230117D03*
X1150492Y227824D03*
X1147590Y253198D03*
X1145587Y339148D03*
X1157251Y636842D03*
X1152485Y764552D03*
X1147468Y766093D03*
X1146674Y778409D03*
X1153485Y813142D03*
X1154985Y802897D03*
X1153229Y848581D03*
X1144494Y1050045D03*
X1154770Y1053324D03*
X1147171Y1058763D03*
X1170447Y90615D03*
X1165135Y90650D03*
X1174768Y99961D03*
X1174284Y443585D03*
X1166868Y442956D03*
X1172172Y433003D03*
X1163298Y465874D03*
X1160756Y665140D03*
X1164732Y802269D03*
X1173122Y802759D03*
X1163579Y850774D03*
X1161535Y844167D03*
X1174461Y914515D03*
X1164338Y1055787D03*
X1189957Y80938D03*
X1183726Y92874D03*
X1178177Y169454D03*
X1185677D03*
X1190958Y208695D03*
X1190593Y226141D03*
X1184086Y223661D03*
X1191748Y392676D03*
X1179184Y403307D03*
X1176699Y451108D03*
X1176138Y458455D03*
X1177566Y778539D03*
X1185516Y844248D03*
X1190968Y848703D03*
X1184340Y851072D03*
X1183012Y856553D03*
X1190213Y856816D03*
X1182602Y879142D03*
X1184652Y886399D03*
X1190431Y888873D03*
X1181151Y919034D03*
X1187871Y916534D03*
X1188219Y951789D03*
X1181438Y978941D03*
X1187714Y984794D03*
X1179906Y1064608D03*
X1191643Y1163114D03*
X1197457Y80938D03*
X1202561Y97475D03*
X1201558Y143740D03*
X1198938Y148277D03*
X1199980Y172190D03*
X1199399Y177616D03*
X1193836Y188727D03*
X1199422Y265896D03*
X1204438Y266114D03*
X1194335Y265701D03*
X1201911Y281982D03*
X1195970Y281716D03*
X1202716Y290755D03*
X1195800Y324000D03*
X1206531Y393858D03*
X1202673Y388000D03*
X1208173Y398583D03*
X1192702Y440489D03*
X1192957Y435158D03*
X1196403Y458572D03*
X1197152Y882399D03*
X1196661Y922901D03*
X1192651Y918534D03*
X1203219Y962789D03*
X1193483Y983053D03*
X1205117Y1112598D03*
X1200313Y1128100D03*
X1205117Y1142519D03*
X1201377Y1149999D03*
X1222383Y60513D03*
X1222511Y85731D03*
X1218204Y103621D03*
X1209542Y100625D03*
X1210121Y141247D03*
X1214608Y143518D03*
X1213708Y152373D03*
X1217550Y183834D03*
X1212265Y171523D03*
X1217723Y172665D03*
X1217660Y178560D03*
X1211795Y192490D03*
X1217840Y200864D03*
X1217863Y207037D03*
X1217929Y212455D03*
X1222738Y228631D03*
X1208797Y281307D03*
X1211892Y339559D03*
X1213173Y377912D03*
Y386500D03*
X1209872Y382047D03*
X1212173Y391496D03*
X1213261Y397912D03*
X1210173Y403500D03*
X1212173Y409000D03*
X1212598Y1112598D03*
X1223818Y1142519D03*
X1210623Y1178467D03*
X1210185Y1185514D03*
X1230924Y86012D03*
X1238479Y102249D03*
X1227017Y94279D03*
X1232204Y110784D03*
X1237204D03*
X1236783Y124663D03*
X1226695Y124283D03*
X1231761Y124879D03*
X1238127Y138838D03*
X1239579Y195176D03*
X1236398Y201683D03*
X1226469Y208864D03*
X1239465Y244571D03*
X1236845Y249108D03*
X1229252Y314890D03*
X1226436Y324518D03*
X1235589Y348015D03*
X1229942Y347937D03*
X1227159Y432124D03*
X1232773Y456559D03*
X1256307Y103411D03*
X1247847Y97667D03*
X1256701D03*
X1241764Y125107D03*
X1250378Y143762D03*
X1244278Y148717D03*
X1253844Y199248D03*
X1246826Y198733D03*
X1248599Y230556D03*
X1252854Y227824D03*
X1243858Y228646D03*
X1246808Y256394D03*
X1241205Y303962D03*
X1252330Y456005D03*
X1254200Y1146600D03*
X1256218Y1175987D03*
X1249363Y1166065D03*
X1255628Y1188345D03*
X1246056Y1205107D03*
X1249072Y1224512D03*
X1245413Y1221062D03*
X1245188Y1232283D03*
X1252057Y1233951D03*
X1254275Y1531334D03*
X1249894Y1527805D03*
X1254275Y1539334D03*
X1250434Y1535334D03*
X1267497Y90650D03*
X1257444Y230117D03*
X1266616Y322456D03*
X1263500Y336000D03*
X1263484Y385644D03*
X1268659Y385123D03*
X1268067Y406060D03*
X1261231Y399918D03*
X1260818Y418996D03*
X1260563Y431730D03*
X1267540Y459330D03*
X1267493Y454214D03*
X1267836Y449045D03*
X1270586Y905324D03*
X1272661Y929858D03*
X1266718Y1142666D03*
X1268593Y1157544D03*
X1267104Y1167768D03*
X1272123D03*
X1271256Y1185205D03*
X1262605Y1187215D03*
X1262298Y1180175D03*
X1260800Y1191096D03*
X1262421Y1195059D03*
X1258237Y1203115D03*
X1273370Y1197626D03*
X1259480Y1221197D03*
X1257348Y1237535D03*
X1269491Y1228760D03*
X1267333Y1531334D03*
X1262891Y1527334D03*
X1267183Y1539334D03*
X1262891Y1535334D03*
X1286088Y92874D03*
X1277130Y99961D03*
X1280539Y169454D03*
X1288039D03*
X1286448Y223661D03*
X1289345Y330655D03*
X1287437Y370010D03*
Y379429D03*
X1273659Y385123D03*
X1280659D03*
X1284333Y391569D03*
X1282760Y409016D03*
X1281737Y461034D03*
Y456034D03*
X1284900Y678800D03*
X1278255Y722241D03*
X1282539Y746076D03*
Y756076D03*
X1279539Y776576D03*
X1281777Y823500D03*
X1285500Y843500D03*
X1281269Y835492D03*
X1285500Y851500D03*
X1279460Y854487D03*
Y859487D03*
Y864487D03*
Y874487D03*
Y879487D03*
X1274264Y898591D03*
X1279460Y884487D03*
X1279299Y898813D03*
X1279460Y889487D03*
X1288500Y904120D03*
X1274400Y914123D03*
X1283493Y929858D03*
X1279693Y919800D03*
X1274670Y919808D03*
X1289547Y941000D03*
X1275050Y1157404D03*
X1275965Y1187232D03*
X1280602Y1185238D03*
X1280395Y1180235D03*
X1275032Y1209589D03*
X1302139Y26325D03*
X1290973Y78245D03*
X1298473D03*
X1304923Y97475D03*
X1301761Y177616D03*
X1302342Y172190D03*
X1296198Y188727D03*
X1293320Y208695D03*
X1292955Y226141D03*
X1296697Y265701D03*
X1301784Y265896D03*
X1304273Y281982D03*
X1298332Y281716D03*
X1305078Y290755D03*
X1292500Y335000D03*
X1299959Y356954D03*
X1299410Y370976D03*
X1293048Y379088D03*
X1298346Y379028D03*
X1293100Y406739D03*
X1299867Y477318D03*
X1299466Y466409D03*
X1299807Y472020D03*
X1299304Y487382D03*
X1301194Y565518D03*
X1305836Y660009D03*
X1298963Y659609D03*
X1289811Y677612D03*
X1303520Y748403D03*
X1291604Y781576D03*
Y776576D03*
Y771435D03*
X1298720Y798975D03*
X1302140Y812625D03*
X1302501Y824747D03*
X1297667Y832150D03*
X1293500Y827500D03*
Y843500D03*
Y835500D03*
X1296687Y839500D03*
X1303628Y841054D03*
X1293500Y851500D03*
X1294000Y863500D03*
X1304050Y874900D03*
X1305250Y889250D03*
X1304000Y884000D03*
X1291129Y892267D03*
X1299895Y896545D03*
X1296466Y903469D03*
X1304949Y928546D03*
X1295453Y928047D03*
X1291059Y917000D03*
X1302000D03*
X1300882Y937144D03*
X1297558Y970216D03*
X1296787Y1291220D03*
X1301769Y1295154D03*
X1314887Y45448D03*
X1311904Y100625D03*
X1320566Y103621D03*
X1319912Y183834D03*
X1314627Y171523D03*
X1320085Y172665D03*
X1320022Y178560D03*
X1314157Y192490D03*
X1320202Y200864D03*
X1320225Y207037D03*
X1320291Y212455D03*
X1309357Y231021D03*
X1306800Y266114D03*
X1311159Y281307D03*
X1313103Y339606D03*
X1312240Y334681D03*
X1308012Y348109D03*
X1320925Y356636D03*
X1315807Y353785D03*
X1308410Y379591D03*
X1310546Y407104D03*
X1308066Y413611D03*
X1308006Y423944D03*
X1307819Y474382D03*
X1319474Y467560D03*
X1319974Y475560D03*
X1319323Y598454D03*
X1319000Y641000D03*
X1313979Y677726D03*
X1319000Y685500D03*
X1321000Y796000D03*
X1313000D03*
X1317000Y799000D03*
X1315000Y811620D03*
X1321000Y804000D03*
X1321972Y825042D03*
X1317276Y826776D03*
X1311277Y837557D03*
X1312359Y845788D03*
X1315104Y852201D03*
X1310678Y856981D03*
X1310125Y863849D03*
X1307500Y880000D03*
X1314641Y874641D03*
X1315603Y889517D03*
X1314500Y911500D03*
Y905000D03*
X1309103Y917000D03*
X1313152Y936605D03*
X1312575Y943974D03*
X1321256Y943815D03*
X1307000Y960500D03*
X1315441Y960000D03*
X1311000Y970124D03*
X1307707Y979870D03*
X1307561Y986951D03*
X1315756Y1039344D03*
X1306385Y1036646D03*
X1319237Y1225428D03*
X1306805Y1279545D03*
X1318287Y1291381D03*
X1324120Y22742D03*
X1328003Y32403D03*
X1328318Y27333D03*
X1336623Y30483D03*
X1328831Y208864D03*
X1325100Y228631D03*
X1322547Y323226D03*
X1332359Y322685D03*
X1331922Y359836D03*
X1335440Y452799D03*
X1329083Y448931D03*
X1332974Y474513D03*
X1326993Y556788D03*
X1327043Y573346D03*
X1327000Y562500D03*
X1326946Y567906D03*
X1338000Y562500D03*
X1335000Y590500D03*
X1327000Y578500D03*
Y583826D03*
Y605000D03*
Y594500D03*
X1333224Y615484D03*
X1327000Y613000D03*
X1335532Y622260D03*
X1338000Y609000D03*
X1335000Y633000D03*
X1327000Y629000D03*
X1327003Y623940D03*
X1338000Y653500D03*
X1327000Y641000D03*
Y657500D03*
Y685500D03*
Y695500D03*
Y700500D03*
X1338000D03*
X1327000Y711500D03*
Y716500D03*
Y732500D03*
X1330295Y746328D03*
X1336661Y753675D03*
Y745675D03*
Y737675D03*
X1330295Y751328D03*
X1330086Y763758D03*
X1324217Y780595D03*
X1336746Y781675D03*
X1329000Y796000D03*
X1325000Y799000D03*
X1337000Y796000D03*
X1333000Y799000D03*
X1330850Y830350D03*
X1331877Y825377D03*
X1337463Y824038D03*
X1326288Y864602D03*
X1332203Y864566D03*
X1323549Y897045D03*
X1336096Y905042D03*
X1338500Y913000D03*
X1326500Y925500D03*
X1333132Y933781D03*
X1336000Y943500D03*
X1323000Y934075D03*
X1326500Y943500D03*
X1325550Y960445D03*
X1334161Y1098518D03*
X1337514Y1104335D03*
X1331237Y1229428D03*
X1335237Y1237428D03*
X1323237D03*
X1332907Y1278568D03*
X1336936Y1278376D03*
X1328903Y1278838D03*
X1351559Y143740D03*
X1348939Y148277D03*
X1344007Y279054D03*
X1347990Y322539D03*
X1341169Y325926D03*
X1349636Y340862D03*
X1346510Y355658D03*
X1349763Y371908D03*
X1346443Y431112D03*
X1352008Y435101D03*
X1352271Y442114D03*
X1346613Y440101D03*
X1352251Y447121D03*
X1346248Y452718D03*
X1340820Y452987D03*
X1352259Y452601D03*
X1346738Y564492D03*
X1339289Y568461D03*
X1342053Y579339D03*
X1346533Y576780D03*
X1340522Y586133D03*
X1343000Y590458D03*
X1346533Y581898D03*
X1344129Y606914D03*
X1344433Y601201D03*
X1339289Y614961D03*
X1344680Y619085D03*
X1346738Y611192D03*
X1346533Y628398D03*
X1342053Y625839D03*
X1340522Y632633D03*
X1343000Y636958D03*
X1346738Y655492D03*
X1339289Y659461D03*
X1346533Y667780D03*
X1342053Y670339D03*
X1346533Y672898D03*
X1340522Y677133D03*
X1343000Y681458D03*
X1350929Y687043D03*
X1340299Y686243D03*
X1346738Y702492D03*
X1346533Y719898D03*
X1339289Y706461D03*
X1342053Y717339D03*
X1346533Y714780D03*
X1340522Y724133D03*
X1343000Y728458D03*
X1344768Y769675D03*
X1345226Y777675D03*
X1341000Y799000D03*
X1345000Y796000D03*
X1348917D03*
X1352817D03*
X1348000Y832000D03*
X1344000Y825500D03*
X1353000Y824000D03*
X1341500Y831000D03*
X1348275Y849171D03*
X1348170Y880104D03*
X1348134Y896278D03*
X1343500Y911000D03*
X1348500Y913500D03*
X1353948Y943603D03*
X1345948D03*
X1349848Y936755D03*
X1343237Y1241428D03*
X1351876Y1260160D03*
X1341226Y1278592D03*
X1346362Y1278700D03*
X1351673D03*
X1360122Y141247D03*
X1364609Y143518D03*
X1363709Y152373D03*
X1355255Y561032D03*
Y652032D03*
X1367000Y811620D03*
X1365000Y804000D03*
X1355000Y811620D03*
X1360000Y824500D03*
X1369000D03*
X1361500Y831500D03*
X1355000Y829500D03*
X1356141Y910359D03*
X1362510Y912490D03*
X1368155Y912270D03*
X1361000Y904000D03*
X1365948Y939475D03*
X1357948Y938842D03*
X1361948Y943603D03*
X1369948D03*
X1365049Y1028416D03*
X1369765Y1015825D03*
X1365314Y1021793D03*
X1366265Y1039880D03*
X1366289Y1098518D03*
X1369642Y1104335D03*
X1360876Y1260160D03*
X1362308Y1278862D03*
X1367828D03*
X1356856D03*
X1382205Y110784D03*
X1387205D03*
X1386784Y124663D03*
X1376696Y124283D03*
X1381762Y124879D03*
X1386399Y201683D03*
X1381519Y218085D03*
X1386846Y249108D03*
X1383634Y342766D03*
X1384265Y334371D03*
Y352371D03*
X1383963Y366675D03*
X1375108Y420838D03*
X1383343Y508228D03*
X1383907Y516591D03*
X1383556Y554388D03*
X1378415Y558795D03*
Y563984D03*
Y569776D03*
X1378957Y584457D03*
X1382997Y581317D03*
X1383425Y593575D03*
X1378415Y605295D03*
Y610484D03*
Y616276D03*
X1384657Y631620D03*
X1378957Y627988D03*
X1378415Y649795D03*
Y654984D03*
Y660776D03*
X1386289Y672488D03*
X1378957Y675457D03*
X1378415Y696795D03*
Y701984D03*
X1378957Y719488D03*
X1378415Y707776D03*
X1385290Y722400D03*
X1381000Y804000D03*
X1385360Y811757D03*
X1375480Y824745D03*
X1381481Y825415D03*
X1386287Y836500D03*
X1384147Y855177D03*
X1378490Y864853D03*
X1385361Y875675D03*
X1385933Y886594D03*
X1386747Y896548D03*
X1377500Y904000D03*
X1382500Y907500D03*
X1380000Y912500D03*
X1372600Y906458D03*
X1374500Y912000D03*
X1378500Y925500D03*
X1382775Y930281D03*
X1373948Y940103D03*
X1373534Y996755D03*
X1381519Y996280D03*
X1373534Y1012325D03*
X1378938Y1000586D03*
X1374059Y1018860D03*
X1379065Y1019069D03*
X1378559Y1038534D03*
X1384784Y1033783D03*
X1385929Y1038665D03*
X1373874Y1032266D03*
X1385152Y1046591D03*
X1384667Y1223783D03*
X1382078Y1238778D03*
X1380855Y1230148D03*
X1380936Y1270898D03*
X1386122Y1270954D03*
X1373032Y1278566D03*
X1388480Y102249D03*
X1397848Y97667D03*
X1391765Y125107D03*
X1400379Y143762D03*
X1394279Y148717D03*
X1388128Y138838D03*
X1389580Y195176D03*
X1396827Y198733D03*
X1402855Y227824D03*
X1398600Y230556D03*
X1393859Y228646D03*
X1389466Y244571D03*
X1396809Y256394D03*
X1395726Y320529D03*
X1395568Y325529D03*
X1395726Y330529D03*
X1395736Y335529D03*
X1395726Y340529D03*
Y345529D03*
Y360529D03*
Y350529D03*
Y355529D03*
X1391896Y365529D03*
X1399884Y367165D03*
X1389557Y424678D03*
X1390271Y417578D03*
X1403085Y460565D03*
X1397079Y531726D03*
Y544726D03*
X1390741Y561000D03*
Y569000D03*
X1397000Y652000D03*
Y660000D03*
Y699000D03*
Y707000D03*
X1391040Y812027D03*
X1398530Y811717D03*
X1402417Y811692D03*
X1400069Y827515D03*
X1401300Y820485D03*
X1402000Y840000D03*
Y848000D03*
X1389404Y847052D03*
X1402000Y864000D03*
Y876000D03*
Y884000D03*
Y892000D03*
X1391764Y887128D03*
X1402000Y900000D03*
X1387520Y905307D03*
X1387753Y912629D03*
X1394891Y914783D03*
X1402187Y908270D03*
X1396869Y958707D03*
X1402064Y965913D03*
X1389192Y992568D03*
X1394885Y999941D03*
X1392031Y1004375D03*
X1390459Y1017180D03*
X1388128Y1027202D03*
X1402809Y1024184D03*
X1389762Y1043055D03*
X1393909Y1032551D03*
X1399807Y1036155D03*
X1392086Y1092743D03*
X1399748Y1098518D03*
X1403101Y1104335D03*
X1396296Y1270918D03*
X1401428D03*
X1391272Y1270920D03*
X1389052Y1303139D03*
X1406308Y103411D03*
X1406702Y97667D03*
X1417498Y90650D03*
X1403845Y199248D03*
X1407445Y230117D03*
X1408854Y381207D03*
X1408254Y398041D03*
X1407844Y411033D03*
X1415674Y421278D03*
X1417856Y448419D03*
X1410903Y470419D03*
Y461919D03*
X1418903Y461419D03*
X1415623Y492268D03*
X1415823Y482165D03*
X1415064Y500202D03*
X1416413Y495649D03*
X1405992Y534909D03*
X1405619Y541135D03*
X1405685Y546553D03*
X1405708Y552726D03*
X1411622Y610548D03*
X1407566Y622285D03*
X1407754Y616905D03*
X1418439Y633736D03*
X1407952Y633724D03*
X1413432Y633716D03*
X1407835Y627713D03*
X1413452Y641817D03*
X1418000Y696000D03*
Y701000D03*
Y717000D03*
X1410000D03*
X1418000Y724000D03*
Y729000D03*
X1404249Y735858D03*
X1418000Y740000D03*
Y745000D03*
X1407482Y750853D03*
X1418000Y761000D03*
X1406867Y783273D03*
X1409115Y773520D03*
X1414597Y792375D03*
X1406483Y811717D03*
X1413449Y823934D03*
X1405402Y819917D03*
X1405500Y844000D03*
Y836000D03*
Y860000D03*
Y880000D03*
Y868000D03*
X1413500Y876000D03*
X1417797Y879501D03*
X1405500Y888000D03*
Y896000D03*
X1417081D03*
X1413500Y892000D03*
Y884000D03*
X1405500Y904000D03*
X1404760Y915186D03*
X1419337Y942285D03*
X1419446Y977192D03*
X1405090Y981903D03*
X1412698Y997590D03*
X1412609Y1008766D03*
X1412759Y1016266D03*
X1416736Y1242194D03*
X1417711Y1301729D03*
X1409900Y1442356D03*
X1422810Y90615D03*
X1427131Y99961D03*
X1430540Y169454D03*
X1434166Y325361D03*
X1434164Y339232D03*
X1434038Y334114D03*
X1435818Y352361D03*
X1434997Y442603D03*
X1427117Y443071D03*
X1432414Y459371D03*
X1427484Y462004D03*
X1427800Y528578D03*
X1421099Y546830D03*
X1435390Y544895D03*
X1435119Y590801D03*
X1434944Y597130D03*
X1420452Y628078D03*
X1430175Y627852D03*
X1425452Y633473D03*
X1433529Y660564D03*
X1426615Y674112D03*
X1429000Y685000D03*
X1425909Y691120D03*
X1433464Y692658D03*
X1433053Y701839D03*
X1431522Y708633D03*
X1434000Y712958D03*
X1430289Y734961D03*
X1429000Y729000D03*
X1434000Y751958D03*
X1433153Y745839D03*
X1435000Y765500D03*
X1434000Y756958D03*
X1435000Y770500D03*
Y802500D03*
Y814500D03*
Y809500D03*
X1434975Y830500D03*
X1435000Y825500D03*
Y846500D03*
X1427000D03*
X1435043Y874694D03*
X1435082Y869475D03*
X1430217Y880162D03*
X1434858Y887763D03*
X1423190Y905295D03*
X1429907Y936998D03*
X1424897Y936777D03*
X1435516Y936000D03*
X1430839Y965546D03*
X1435229Y1104335D03*
X1420736Y1226194D03*
X1424736Y1238194D03*
X1432736Y1230194D03*
X1421964Y1502813D03*
X1442656Y76899D03*
X1450156D03*
X1436089Y92874D03*
X1451301Y148277D03*
X1438040Y169454D03*
X1451762Y177616D03*
X1446199Y188727D03*
X1443321Y208695D03*
X1442956Y226141D03*
X1436449Y223661D03*
X1451785Y265896D03*
X1446698Y265701D03*
X1448333Y281716D03*
X1449060Y329861D03*
Y320861D03*
X1438829Y329861D03*
X1437064Y320861D03*
X1448500Y340575D03*
X1439712Y336673D03*
X1440420Y346833D03*
X1441180Y354909D03*
X1448572Y349441D03*
X1443041Y363648D03*
X1442633Y371502D03*
X1440523Y382747D03*
X1436930Y461818D03*
X1439462Y529929D03*
X1449393Y566797D03*
X1449993Y578405D03*
X1443775Y596089D03*
X1448994Y596782D03*
X1437770Y628242D03*
X1437738Y686992D03*
X1451976Y693844D03*
X1437533Y704398D03*
Y699280D03*
X1438930Y716363D03*
X1446860Y730735D03*
X1437738Y730992D03*
X1437533Y743280D03*
Y748398D03*
X1447289Y776461D03*
X1446000Y770500D03*
X1451000Y793458D03*
Y798458D03*
X1450253Y787339D03*
X1447000Y810500D03*
Y818500D03*
X1448000Y834500D03*
X1449000Y844500D03*
X1448581Y924436D03*
X1448743Y935588D03*
X1441088Y976409D03*
X1440700Y981763D03*
X1440869Y1010256D03*
X1447361Y1273222D03*
X1457347Y31518D03*
X1457829Y26425D03*
X1461905Y100625D03*
X1454924Y97475D03*
X1462484Y141247D03*
X1466971Y143518D03*
X1453921Y143740D03*
X1466071Y152373D03*
X1452343Y172190D03*
X1464158Y192490D03*
X1456801Y266114D03*
X1461160Y281307D03*
X1454274Y281982D03*
X1455079Y290755D03*
X1463145Y391579D03*
X1456958Y556317D03*
X1459146Y565573D03*
X1455419Y578986D03*
X1454944Y596729D03*
X1461474Y655807D03*
X1468372Y673812D03*
X1454504Y777575D03*
X1454533Y784780D03*
X1454738Y772492D03*
X1454533Y789898D03*
X1453102Y821102D03*
X1454541Y831339D03*
X1453102Y826500D03*
X1452619Y836457D03*
X1457174Y874859D03*
X1461113Y871389D03*
X1462391Y892822D03*
X1462500Y905295D03*
X1467508Y905405D03*
X1458202Y960288D03*
X1457937Y966712D03*
X1467096Y988813D03*
X1458892Y1007522D03*
X1465658Y1006648D03*
X1463025Y1018307D03*
X1459267Y1013678D03*
X1456280Y1023405D03*
X1459683Y1028377D03*
X1452784Y1289102D03*
X1457794Y1292726D03*
X1474746Y60513D03*
X1474874Y85731D03*
X1483287Y86012D03*
X1479380Y94279D03*
X1470567Y103621D03*
X1484567Y110784D03*
X1479058Y124283D03*
X1484124Y124879D03*
X1469913Y183834D03*
X1470023Y178560D03*
X1470086Y172665D03*
X1469433Y190185D03*
X1478800Y196665D03*
X1470203Y200864D03*
X1470292Y212455D03*
X1470226Y207037D03*
X1475101Y228631D03*
X1475264Y680933D03*
X1476716Y704398D03*
X1479500Y689630D03*
Y697630D03*
X1479759Y720885D03*
X1469957Y706957D03*
X1479794Y709388D03*
X1472000Y727500D03*
X1480000Y731500D03*
X1476716Y748398D03*
X1480000Y739500D03*
X1471006Y744818D03*
X1470801Y739280D03*
X1479665Y754555D03*
X1474883Y868206D03*
X1473387Y897425D03*
X1482195Y885807D03*
X1472000Y929500D03*
X1472500Y935324D03*
X1480144Y946880D03*
X1480414Y952214D03*
X1479196Y970000D03*
X1480414Y975064D03*
X1475096Y988813D03*
X1483096D03*
X1482535Y1024254D03*
X1471854Y1035088D03*
X1474384Y1165091D03*
X1480675Y1202103D03*
X1483308Y1214372D03*
X1479063Y1218169D03*
X1489556Y17645D03*
X1489829Y29424D03*
X1490563Y23043D03*
X1490842Y102249D03*
X1500210Y97667D03*
X1489567Y110784D03*
X1494127Y125107D03*
X1489146Y124663D03*
X1496641Y148717D03*
X1490490Y138838D03*
X1491942Y195176D03*
X1499189Y198733D03*
X1488761Y201683D03*
X1496221Y228646D03*
X1491828Y244571D03*
X1489208Y249108D03*
X1499171Y256394D03*
X1486860Y327200D03*
X1500659Y330024D03*
X1495605Y322700D03*
X1487318Y318200D03*
X1500386Y344642D03*
X1486913Y340327D03*
X1495689Y332534D03*
X1495521Y340700D03*
Y349681D03*
X1495925Y358700D03*
X1499839Y354001D03*
X1486890Y368576D03*
X1488799Y547918D03*
X1488731Y739500D03*
X1496629Y765000D03*
X1493301Y776911D03*
X1496814Y773000D03*
X1497000Y781000D03*
X1499633Y787794D03*
X1493716Y789898D03*
X1495170Y796670D03*
X1487050Y809413D03*
X1496845Y809000D03*
X1496806Y817000D03*
X1486386Y825296D03*
X1493038Y833898D03*
X1495240Y825000D03*
X1500563Y881339D03*
X1500063Y870339D03*
X1494954Y895264D03*
X1500417Y915191D03*
X1484824Y927324D03*
X1490000Y928655D03*
X1485500Y932500D03*
X1498983Y944443D03*
X1495500Y972500D03*
X1489500D03*
X1491096Y988813D03*
X1499096D03*
X1490235Y1004816D03*
X1487266Y1002046D03*
X1495339Y1021954D03*
X1486030Y1016827D03*
X1491877D03*
X1496185Y1102091D03*
Y1114691D03*
Y1127291D03*
Y1139891D03*
Y1152491D03*
Y1165091D03*
Y1177691D03*
X1489793Y1207737D03*
X1497693Y1230407D03*
X1508670Y103411D03*
X1509064Y97667D03*
X1502741Y143762D03*
X1506207Y199248D03*
X1509807Y230117D03*
X1500962Y230556D03*
X1505217Y227824D03*
X1501000Y317500D03*
X1501684Y336561D03*
X1516838Y347422D03*
X1515909Y354601D03*
X1516636Y458711D03*
X1511691Y546805D03*
X1502158Y899479D03*
X1504208Y909740D03*
X1506151Y915726D03*
X1509274Y921226D03*
X1516139Y918399D03*
X1511256Y916334D03*
X1509500Y937000D03*
Y944138D03*
X1516500Y947500D03*
X1504085Y943714D03*
X1501812Y938397D03*
X1509500Y950500D03*
X1507096Y988813D03*
X1515096D03*
X1513286Y1012354D03*
X1507831Y1009354D03*
X1513286Y1024954D03*
X1507831Y1021954D03*
X1501640Y1105091D03*
Y1117691D03*
Y1130291D03*
Y1142891D03*
Y1155491D03*
Y1168091D03*
Y1180691D03*
X1507232Y1214967D03*
X1508356Y1220068D03*
X1511550Y1224260D03*
X1506807Y1234921D03*
X1507058Y1229402D03*
X1525172Y90615D03*
X1519860Y90650D03*
X1529493Y99961D03*
X1532902Y169454D03*
X1519321Y378600D03*
X1532975Y546062D03*
X1519185Y615600D03*
X1520729Y634190D03*
X1529000Y884006D03*
X1525022Y909558D03*
X1526206Y918341D03*
X1521500Y947500D03*
X1528500Y947612D03*
X1529097Y967090D03*
X1517470Y967471D03*
X1531096Y988813D03*
X1523096D03*
X1527096Y997860D03*
X1526810Y1025090D03*
X1522904Y1021256D03*
X1521939Y1040818D03*
X1522099Y1035521D03*
X1531993Y1056453D03*
X1531961Y1050849D03*
X1524953Y1051037D03*
X1527559Y1143390D03*
X1545018Y76899D03*
X1538451Y92874D03*
X1540402Y169454D03*
X1548561Y188727D03*
X1545683Y208695D03*
X1538811Y223661D03*
X1545318Y226141D03*
X1549060Y265701D03*
X1545583Y316363D03*
X1539140Y320863D03*
X1545636Y325363D03*
X1542797Y329863D03*
X1545846Y334363D03*
X1544951Y343363D03*
X1545434Y352363D03*
X1548080Y910757D03*
X1547644Y903060D03*
X1546224Y1142520D03*
X1536909Y1151870D03*
X1538767Y1146271D03*
X1536909Y1159350D03*
X1540649Y1155610D03*
X1538845Y1168638D03*
X1540487Y1163381D03*
X1552518Y76899D03*
X1564267Y100625D03*
X1557286Y97475D03*
X1564846Y141247D03*
X1556283Y143740D03*
X1553663Y148277D03*
X1554705Y172190D03*
X1554124Y177616D03*
X1559163Y266114D03*
X1554147Y265896D03*
X1563522Y281307D03*
X1556636Y281982D03*
X1550695Y281716D03*
X1557441Y290755D03*
X1550931Y305158D03*
X1553534Y327337D03*
X1553597Y336601D03*
X1551175Y347283D03*
X1556588Y545528D03*
X1564670Y650122D03*
X1565132Y668153D03*
Y677843D03*
X1557444Y1135040D03*
X1553738Y1194917D03*
X1564960Y1217322D03*
X1577108Y60513D03*
X1577236Y85731D03*
X1581742Y94279D03*
X1572929Y103621D03*
X1581420Y124283D03*
X1569333Y143518D03*
X1568433Y152373D03*
X1572275Y183834D03*
X1572385Y178560D03*
X1572448Y172665D03*
X1571795Y190185D03*
X1566520Y192490D03*
X1572565Y200864D03*
X1572654Y212455D03*
X1572588Y207037D03*
X1581194Y208864D03*
X1577463Y228631D03*
X1578420Y338309D03*
X1574775Y344127D03*
X1575935Y382109D03*
X1577862Y554121D03*
X1570200Y551040D03*
X1579760Y595500D03*
X1574760Y606929D03*
X1579260Y604567D03*
X1574720Y618400D03*
X1575001Y612592D03*
X1580418Y610072D03*
X1580354Y616317D03*
X1577077Y631712D03*
X1571888Y649380D03*
X1576181Y1217322D03*
X1585649Y86012D03*
X1593204Y102249D03*
X1586929Y110784D03*
X1591929D03*
X1596489Y125107D03*
X1586486Y124879D03*
X1591508Y124663D03*
X1592852Y138838D03*
X1594304Y195176D03*
X1591123Y201683D03*
X1594190Y244571D03*
X1591570Y249108D03*
X1595069Y337361D03*
X1595109Y342663D03*
X1594466Y350984D03*
X1586760Y544000D03*
X1594760Y568000D03*
X1595429Y1055975D03*
X1596261Y1062847D03*
X1583661Y1217322D03*
Y1209842D03*
X1587401Y1213582D03*
X1596790Y1442557D03*
X1596038Y1492000D03*
X1590748Y1523377D03*
X1602572Y97667D03*
X1611032Y103411D03*
X1611426Y97667D03*
X1605103Y143762D03*
X1599003Y148717D03*
X1608569Y199248D03*
X1601551Y198733D03*
X1603324Y230556D03*
X1607579Y227824D03*
X1612169Y230117D03*
X1598583Y228646D03*
X1604677Y253198D03*
X1599527Y404718D03*
Y412718D03*
X1600262Y479577D03*
X1614338Y636842D03*
X1606190Y803774D03*
X1606709Y819165D03*
X1604258Y1058763D03*
X1601581Y1050045D03*
X1611857Y1053324D03*
X1600008Y1488492D03*
X1601500Y1514500D03*
X1608500Y1506000D03*
X1613790Y1531334D03*
X1609348Y1527334D03*
X1613790Y1523334D03*
X1604000Y1519000D03*
X1600732Y1539334D03*
X1609348Y1535334D03*
X1622222Y90650D03*
X1627534Y90615D03*
X1617595Y399648D03*
X1630650Y443035D03*
X1623955Y442956D03*
X1629259Y433003D03*
X1620385Y465874D03*
X1618538Y618288D03*
X1617843Y665140D03*
X1621425Y1055787D03*
X1646707Y76900D03*
X1640813Y92874D03*
X1631855Y99961D03*
X1635264Y169454D03*
X1642764D03*
X1641173Y223661D03*
X1636271Y403307D03*
X1632439Y452265D03*
X1633225Y458455D03*
X1635185Y446595D03*
X1644552Y871353D03*
X1635176Y886761D03*
X1644718Y909263D03*
X1635000Y919263D03*
X1644325Y942120D03*
X1637771Y952120D03*
X1636993Y1064608D03*
X1640581Y1551907D03*
X1654207Y76900D03*
X1659648Y97475D03*
X1658645Y143740D03*
X1656025Y148277D03*
X1656486Y177616D03*
X1657067Y172190D03*
X1650923Y188727D03*
X1648045Y208695D03*
X1647680Y226141D03*
X1656509Y265896D03*
X1661525Y266114D03*
X1651422Y265701D03*
X1653057Y281716D03*
X1658998Y281982D03*
X1659803Y290755D03*
X1649061Y336546D03*
X1659760Y388000D03*
X1650044Y435158D03*
X1649789Y440489D03*
X1653490Y458572D03*
X1647402Y881460D03*
X1647565Y981432D03*
X1662204Y1112598D03*
X1657400Y1128100D03*
X1662204Y1142519D03*
X1658464Y1149999D03*
X1648730Y1163114D03*
X1679470Y60513D03*
X1679598Y85731D03*
X1675291Y103621D03*
X1666629Y100625D03*
X1667208Y141247D03*
X1671695Y143518D03*
X1670795Y152373D03*
X1674637Y183834D03*
X1674810Y172665D03*
X1674747Y178560D03*
X1674157Y190185D03*
X1668882Y192490D03*
X1674927Y200864D03*
X1674950Y207037D03*
X1675016Y212455D03*
X1664082Y231021D03*
X1665884Y281307D03*
X1668979Y339559D03*
X1670260Y377912D03*
X1669260Y391496D03*
X1663618Y393858D03*
X1666959Y382047D03*
X1670260Y386500D03*
X1669260Y409000D03*
X1665260Y398583D03*
X1670348Y397912D03*
X1667260Y403500D03*
X1667815Y1064640D03*
X1667272Y1185514D03*
X1667710Y1178467D03*
X1688011Y86012D03*
X1695566Y102249D03*
X1684104Y94279D03*
X1694291Y110784D03*
X1689291D03*
X1683782Y124283D03*
X1693870Y124663D03*
X1688848Y124879D03*
X1695214Y138838D03*
X1693485Y201683D03*
X1683556Y208864D03*
X1679825Y228631D03*
X1693932Y249108D03*
X1686339Y314890D03*
X1683523Y324518D03*
X1687424Y347937D03*
X1692676Y348015D03*
X1691182Y357016D03*
X1680905Y1142519D03*
X1704934Y97667D03*
X1698851Y125107D03*
X1707465Y143762D03*
X1701365Y148717D03*
X1696666Y195176D03*
X1710931Y199248D03*
X1703913Y198733D03*
X1705686Y230556D03*
X1709941Y228747D03*
X1700945Y228646D03*
X1696552Y244571D03*
X1703895Y256394D03*
X1699205Y368854D03*
X1699391Y433834D03*
X1704945Y442080D03*
X1698716Y550065D03*
X1711333Y1146609D03*
X1706450Y1173065D03*
X1704760Y1202200D03*
X1706159Y1224512D03*
X1702500Y1221062D03*
X1702275Y1232283D03*
X1709144Y1233951D03*
X1713394Y103411D03*
X1713788Y97667D03*
X1724584Y90650D03*
X1714531Y230117D03*
X1720571Y385644D03*
X1725746Y385123D03*
X1718318Y399918D03*
X1725154Y406060D03*
X1717905Y418996D03*
X1717650Y431730D03*
X1724627Y459330D03*
X1724580Y454214D03*
X1724923Y449045D03*
X1723805Y1142666D03*
X1725680Y1157544D03*
X1724191Y1167768D03*
X1713239Y1176038D03*
X1728343Y1185205D03*
X1719692Y1187215D03*
X1719385Y1180175D03*
X1712715Y1188500D03*
X1717406Y1195603D03*
X1715324Y1203115D03*
X1716567Y1221197D03*
X1714435Y1237535D03*
X1726578Y1228760D03*
X1712966Y1229841D03*
X1743175Y92874D03*
X1729896Y90615D03*
X1734217Y99961D03*
X1737626Y169454D03*
X1743535Y223661D03*
X1744524Y379429D03*
X1730746Y385123D03*
X1737746D03*
X1741420Y391569D03*
X1739847Y409016D03*
X1738824Y456034D03*
Y461034D03*
X1739917Y1146937D03*
X1732137Y1157404D03*
X1729210Y1167768D03*
X1733052Y1187310D03*
X1737689Y1185238D03*
X1737482Y1180235D03*
X1730457Y1197626D03*
X1731619Y1210089D03*
X1750752Y82285D03*
X1758252D03*
X1745126Y169454D03*
X1758848Y177616D03*
X1759429Y172190D03*
X1753285Y188727D03*
X1750407Y208695D03*
X1750042Y226141D03*
X1753784Y265701D03*
X1758871Y265896D03*
X1755419Y281716D03*
X1752497Y371076D03*
X1750135Y379088D03*
X1755433Y379028D03*
X1750187Y406739D03*
X1756894Y472020D03*
X1756553Y466409D03*
X1756954Y477318D03*
X1756391Y487382D03*
X1745824Y987058D03*
X1759569Y1021944D03*
X1759947Y1599029D03*
X1750685Y1618504D03*
X1762010Y97475D03*
X1768991Y100625D03*
X1776999Y183834D03*
X1771244Y192490D03*
X1776519Y190185D03*
X1763887Y266114D03*
X1768246Y281307D03*
X1761360Y281982D03*
X1762165Y290755D03*
X1765497Y379591D03*
X1767633Y407104D03*
X1765093Y423944D03*
X1765153Y413611D03*
X1764906Y474382D03*
X1776561Y467560D03*
X1777061Y475560D03*
X1768844Y1023694D03*
X1772188Y1428369D03*
X1766313Y1580198D03*
X1761072Y1590719D03*
X1765040Y1599511D03*
X1764422Y1640303D03*
X1762041Y1631511D03*
X1768422Y1632245D03*
X1773820Y1631238D03*
X1781832Y60513D03*
X1781960Y85731D03*
X1790712Y81713D03*
X1786466Y94279D03*
X1777172Y172665D03*
X1777109Y178560D03*
X1777289Y200864D03*
X1777378Y212455D03*
X1777312Y207037D03*
X1785918Y208864D03*
X1781559Y219379D03*
X1782187Y228631D03*
X1786170Y448931D03*
X1792527Y452799D03*
X1790061Y474513D03*
X1779404Y826570D03*
X1781263Y964660D03*
X1786863Y985060D03*
X1779033Y1023432D03*
X1792613Y1079394D03*
X1781559Y1082075D03*
X1783278Y1208140D03*
X1791099Y1260421D03*
X1787745Y1437765D03*
X1777131Y1604357D03*
X1809095Y435101D03*
X1803700Y440101D03*
X1803530Y431112D03*
X1809358Y442114D03*
X1803335Y452718D03*
X1809346Y452601D03*
X1797907Y452987D03*
X1809338Y447121D03*
X1802363Y989660D03*
X1801961Y1081717D03*
X1795819Y1088553D03*
X1796990Y1134564D03*
X1797924Y1148330D03*
X1796607Y1200108D03*
X1806835Y1214668D03*
X1800489Y1220598D03*
X1807243Y1219955D03*
X1802670Y1210905D03*
X1805126Y1225745D03*
X1795374Y1444543D03*
X1802813Y1464015D03*
X1817439Y447101D03*
X1816756Y1089145D03*
Y1094145D03*
X1816235Y1083970D03*
X1810346Y1082250D03*
X1816756Y1101145D03*
X1810310Y1104819D03*
X1812130Y1205349D03*
X1814741Y1217093D03*
X1812202Y1432624D03*
G54D12*
X15916Y1041679D03*
X28318D03*
X50051Y1041371D03*
X37649D03*
X438119Y1234726D03*
X450521D03*
X476828D03*
X489230D03*
X862606Y1050682D03*
X875008D03*
X896741Y1050374D03*
X884339D03*
X926583Y1050682D03*
X938985D03*
X960718Y1050374D03*
X948316D03*
X1352293Y1234726D03*
X1364695D03*
X1391002D03*
X1403404D03*
X1770563Y1051168D03*
X1782965D03*
X1804698Y1050860D03*
X1792296D03*
G54D21*
X19859Y1520657D03*
X18879Y1534334D03*
X69049Y847718D03*
X281594Y1211712D03*
X270374Y1215452D03*
X336755Y1143489D03*
X341266Y1171956D03*
X415015Y1088205D03*
X418495Y1106867D03*
X422665Y1325323D03*
X426665D03*
X423200Y1397500D03*
X430878Y1081816D03*
X431114Y1272701D03*
X450623Y1106867D03*
X484082D03*
X513324Y693892D03*
X515357Y698253D03*
X511359Y698494D03*
X510654Y703806D03*
X523299Y709313D03*
X519072Y709183D03*
X516210Y1106867D03*
X518576Y1273004D03*
X525712Y1272992D03*
X793842Y1143384D03*
X798353Y1172011D03*
X814080Y864464D03*
X834465Y884538D03*
X847098Y891213D03*
X897636Y839406D03*
X889336Y1452554D03*
X889244Y1468859D03*
X903817Y879770D03*
X919038Y579378D03*
X929557Y889258D03*
X917744Y1453573D03*
X959545Y918306D03*
X1184547Y1215452D03*
X1250928Y1142828D03*
X1255439Y1172008D03*
X1253904Y1519645D03*
X1323205Y867665D03*
X1329189Y1088205D03*
X1332669Y1106867D03*
X1324886Y1278962D03*
X1364797Y1106867D03*
X1375193Y811724D03*
X1379858Y1420701D03*
X1398256Y1106867D03*
X1409066Y1272899D03*
X1405066D03*
X1413066D03*
X1430384Y1106867D03*
X1439031Y957683D03*
X1443769Y1562173D03*
X1468869Y1018469D03*
X1598574Y1543373D03*
X1641634Y1215452D03*
X1708015Y1142700D03*
X1712526Y1171950D03*
X1809078Y2165771D03*
X1806706Y2180760D03*
X1812366Y2063809D03*
X1822066Y2054109D03*
X1812366D03*
X1813087Y2087512D03*
X1825427Y2104853D03*
X1817378Y2165771D03*
X1815006Y2180760D03*
X1841295Y2065122D03*
X1832995D03*
X1833649Y2057507D03*
X1830872Y2083503D03*
X1840875Y2083215D03*
X1837649Y2072324D03*
X1829349D03*
X1833727Y2104853D03*
X1835862Y2121040D03*
X1833506Y2185252D03*
X1852032Y2052576D03*
X1854559Y2077931D03*
X1851762Y2121040D03*
X1854796Y2170548D03*
X1846496D03*
X1855978Y2185118D03*
X1847678D03*
X1859032Y2052576D03*
X1870505Y2064156D03*
X1860338Y2071384D03*
X1874505Y2078973D03*
X1860234Y2157701D03*
X1867072Y2174962D03*
X1864547Y2185020D03*
X1890039Y2066092D03*
X1878805Y2064156D03*
X1886128Y2075919D03*
X1882805Y2078973D03*
X1876497Y2070684D03*
X1884535Y2155415D03*
X1882972Y2174962D03*
X1882111Y2179074D03*
X1874932Y2180585D03*
X1881852Y2196600D03*
X1886699Y2183170D03*
X1876697D03*
X1905939Y2066092D03*
X1893118Y2054585D03*
X1905944Y2055424D03*
X1898342Y2062143D03*
X1901295Y2072745D03*
X1892835Y2155415D03*
X1902872Y2178531D03*
X1894572D03*
X1893087Y2168011D03*
X1896403Y2185019D03*
X1917195Y2072745D03*
X1917550Y2158451D03*
X1909250D03*
X1922010Y2151829D03*
X1913710D03*
X1921855Y2172152D03*
X1936295Y2074343D03*
X1935195Y2155918D03*
X1936377Y2163810D03*
X1924735Y2178131D03*
X1936212Y2173508D03*
X1930155Y2172152D03*
X1931738Y2182647D03*
X1923438D03*
X1941040Y2070124D03*
X1951095Y2155918D03*
X1946077Y2163810D03*
X1969128Y2161283D03*
X1959428D03*
X1969128Y2151583D03*
X1959428D03*
G54D30*
X51043Y60709D03*
Y150197D03*
X153405Y60709D03*
Y150197D03*
X190325Y455492D03*
Y503760D03*
Y583957D03*
Y636752D03*
X255767Y60709D03*
Y150197D03*
X279360Y368760D03*
Y421555D03*
Y501752D03*
Y550020D03*
X358129Y60709D03*
Y150197D03*
X508130Y60709D03*
Y150197D03*
X610492Y60709D03*
Y150197D03*
X647411Y455492D03*
Y503760D03*
Y583957D03*
Y636752D03*
X712854Y60709D03*
Y150197D03*
X736446Y368760D03*
Y421555D03*
Y501752D03*
Y550020D03*
X815216Y60709D03*
Y150197D03*
X965216Y60709D03*
Y150197D03*
X1067578Y60709D03*
Y150197D03*
X1104498Y455492D03*
Y503760D03*
Y583957D03*
Y636752D03*
X1169940Y60709D03*
Y150197D03*
X1193533Y368760D03*
Y421555D03*
Y501752D03*
Y550020D03*
X1272302Y60709D03*
Y150197D03*
X1422303Y60709D03*
Y150197D03*
X1524665Y60709D03*
Y150197D03*
X1561585Y455492D03*
Y503760D03*
Y583957D03*
Y636752D03*
X1627027Y60709D03*
Y150197D03*
X1650620Y368760D03*
Y421555D03*
Y501752D03*
Y550020D03*
X1729389Y60709D03*
Y150197D03*
G54D22*
X23622Y1604724D03*
X62205Y765197D03*
X74016Y333464D03*
X102224Y70866D03*
X409488Y1604724D03*
X433130Y70866D03*
X463387Y286221D03*
X463386Y765197D03*
X661674Y23622D03*
X785039Y1547638D03*
X890217Y23622D03*
X920473Y765196D03*
X1055905Y1547637D03*
X1118760Y23622D03*
X1347303Y70866D03*
X1377559Y286220D03*
Y765197D03*
X1431457Y1604724D03*
X1575846Y23622D03*
X1766929Y333464D03*
X1778740Y765197D03*
X1795010Y23622D03*
X1817323Y1604724D03*
G54D13*
X17874Y1041679D03*
X26360D03*
X48093D03*
X39607D03*
X440077Y1234726D03*
X448563D03*
X478786D03*
X487272D03*
X864564Y1050682D03*
X873050D03*
X894783D03*
X886297D03*
X928541D03*
X937027D03*
X958760D03*
X950274D03*
X1362737Y1234726D03*
X1354251D03*
X1392960D03*
X1401446D03*
X1772521Y1051168D03*
X1781007D03*
X1802740D03*
X1794254D03*
G54D40*
X109882Y1453504D03*
Y1468859D03*
Y1484213D03*
Y1499567D03*
Y1514922D03*
Y1555867D03*
Y1571221D03*
Y1586575D03*
Y1601930D03*
Y1617284D03*
X127205Y1453504D03*
X118543Y1457835D03*
X127205Y1468859D03*
X118543Y1473189D03*
X127205Y1484213D03*
X118543Y1488544D03*
X127205Y1499567D03*
Y1514922D03*
X118543Y1503898D03*
Y1519252D03*
X127205Y1555867D03*
X118543Y1560197D03*
X127205Y1571221D03*
X118543Y1575552D03*
X127205Y1586575D03*
X118543Y1590906D03*
X127205Y1601930D03*
X118543Y1606260D03*
X127205Y1617284D03*
X118543Y1621615D03*
X144528Y1453504D03*
X135866Y1457835D03*
X144528Y1468859D03*
X135866Y1473189D03*
X144528Y1484213D03*
X135866Y1488544D03*
X144528Y1499567D03*
Y1514922D03*
X135866Y1503898D03*
Y1519252D03*
X144528Y1555867D03*
X135866Y1560197D03*
X144528Y1571221D03*
X135866Y1575552D03*
X144528Y1586575D03*
X135866Y1590906D03*
X144528Y1601930D03*
X135866Y1606260D03*
X144528Y1617284D03*
X135866Y1621615D03*
X161850Y1453504D03*
X153189Y1457835D03*
X161850Y1468859D03*
X153189Y1473189D03*
X161850Y1484213D03*
X153189Y1488544D03*
X161850Y1499567D03*
Y1514922D03*
X153189Y1503898D03*
Y1519252D03*
X161850Y1555867D03*
X153189Y1560197D03*
X161850Y1571221D03*
X153189Y1575552D03*
X161850Y1586575D03*
X153189Y1590906D03*
X161850Y1601930D03*
X153189Y1606260D03*
X161850Y1617284D03*
X153189Y1621615D03*
X179173Y1453504D03*
X170512Y1457835D03*
X179173Y1468859D03*
X170512Y1473189D03*
X179173Y1484213D03*
X170512Y1488544D03*
X179173Y1499567D03*
Y1514922D03*
X170512Y1503898D03*
Y1519252D03*
X179173Y1555867D03*
X170512Y1560197D03*
X179173Y1571221D03*
X170512Y1575552D03*
X179173Y1586575D03*
X170512Y1590906D03*
X179173Y1601930D03*
X170512Y1606260D03*
X179173Y1617284D03*
X170512Y1621615D03*
X187835Y1457835D03*
Y1473189D03*
Y1488544D03*
Y1503898D03*
Y1519252D03*
Y1560197D03*
Y1575552D03*
Y1590906D03*
Y1606260D03*
Y1621615D03*
X283110Y1453504D03*
X291771Y1457835D03*
X283110Y1468859D03*
X291771Y1473189D03*
X283110Y1484213D03*
X291771Y1488544D03*
X283110Y1499567D03*
X291771Y1503898D03*
X283110Y1514922D03*
X291771Y1519252D03*
X283110Y1555867D03*
X291771Y1560197D03*
X283110Y1571221D03*
X291771Y1575552D03*
X283110Y1586575D03*
X291771Y1590906D03*
X283110Y1601930D03*
X291771Y1606260D03*
X283110Y1617284D03*
X291771Y1621615D03*
X300433Y1453504D03*
X309094Y1457835D03*
X300433Y1468859D03*
X309094Y1473189D03*
X300433Y1484213D03*
X309094Y1488544D03*
X300433Y1499567D03*
X309094Y1503898D03*
X300433Y1514922D03*
X309094Y1519252D03*
X300433Y1555867D03*
X309094Y1560197D03*
X300433Y1571221D03*
X309094Y1575552D03*
X300433Y1586575D03*
X309094Y1590906D03*
X300433Y1601930D03*
X309094Y1606260D03*
X300433Y1617284D03*
X309094Y1621615D03*
X317756Y1453504D03*
X326417Y1457835D03*
X317756Y1468859D03*
X326417Y1473189D03*
X317756Y1484213D03*
X326417Y1488544D03*
X317756Y1499567D03*
X326417Y1503898D03*
X317756Y1514922D03*
X326417Y1519252D03*
X317756Y1555867D03*
X326417Y1560197D03*
X317756Y1571221D03*
X326417Y1575552D03*
X317756Y1586575D03*
X326417Y1590906D03*
X317756Y1601930D03*
X326417Y1606260D03*
X317756Y1617284D03*
X326417Y1621615D03*
X335078Y1453504D03*
X343740Y1457835D03*
X335078Y1468859D03*
X343740Y1473189D03*
X335078Y1484213D03*
X343740Y1488544D03*
X335078Y1499567D03*
X343740Y1503898D03*
X335078Y1514922D03*
X343740Y1519252D03*
X335078Y1555867D03*
X343740Y1560197D03*
X335078Y1571221D03*
X343740Y1575552D03*
X335078Y1586575D03*
X343740Y1590906D03*
X335078Y1601930D03*
X343740Y1606260D03*
X335078Y1617284D03*
X343740Y1621615D03*
X352401Y1453504D03*
X361063Y1457835D03*
X352401Y1468859D03*
X361063Y1473189D03*
X352401Y1484213D03*
X361063Y1488544D03*
X352401Y1499567D03*
X361063Y1503898D03*
X352401Y1514922D03*
X361063Y1519252D03*
X352401Y1555867D03*
X361063Y1560197D03*
X352401Y1571221D03*
X361063Y1575552D03*
X352401Y1586575D03*
X361063Y1590906D03*
X352401Y1601930D03*
X361063Y1606260D03*
X352401Y1617284D03*
X361063Y1621615D03*
X456339Y1453504D03*
Y1468859D03*
Y1484213D03*
Y1499567D03*
Y1514922D03*
Y1555867D03*
Y1571221D03*
Y1586575D03*
Y1601930D03*
Y1617284D03*
X473662Y1453504D03*
X465000Y1457835D03*
X473662Y1468859D03*
X465000Y1473189D03*
X473662Y1484213D03*
X465000Y1488544D03*
X473662Y1499567D03*
Y1514922D03*
X465000Y1503898D03*
Y1519252D03*
X473662Y1555867D03*
X465000Y1560197D03*
X473662Y1571221D03*
X465000Y1575552D03*
X473662Y1586575D03*
X465000Y1590906D03*
X473662Y1601930D03*
X465000Y1606260D03*
X473662Y1617284D03*
X465000Y1621615D03*
X490985Y1453504D03*
X482323Y1457835D03*
X490985Y1468859D03*
X482323Y1473189D03*
X490985Y1484213D03*
X482323Y1488544D03*
X490985Y1499567D03*
Y1514922D03*
X482323Y1503898D03*
Y1519252D03*
X490985Y1555867D03*
X482323Y1560197D03*
X490985Y1571221D03*
X482323Y1575552D03*
X490985Y1586575D03*
X482323Y1590906D03*
X490985Y1601930D03*
X482323Y1606260D03*
X490985Y1617284D03*
X482323Y1621615D03*
X508307Y1453504D03*
X499646Y1457835D03*
X508307Y1468859D03*
X499646Y1473189D03*
X508307Y1484213D03*
X499646Y1488544D03*
X508307Y1499567D03*
Y1514922D03*
X499646Y1503898D03*
Y1519252D03*
X508307Y1555867D03*
X499646Y1560197D03*
X508307Y1571221D03*
X499646Y1575552D03*
X508307Y1586575D03*
X499646Y1590906D03*
X508307Y1601930D03*
X499646Y1606260D03*
X508307Y1617284D03*
X499646Y1621615D03*
X516969Y1457835D03*
Y1473189D03*
Y1488544D03*
Y1503898D03*
Y1519252D03*
Y1560197D03*
Y1575552D03*
Y1590906D03*
Y1606260D03*
Y1621615D03*
X525630Y1453504D03*
X534292Y1457835D03*
X525630Y1468859D03*
X534292Y1473189D03*
X525630Y1484213D03*
X534292Y1488544D03*
X525630Y1499567D03*
X534292Y1503898D03*
X525630Y1514922D03*
X534292Y1519252D03*
X525630Y1555867D03*
X534292Y1560197D03*
X525630Y1571221D03*
X534292Y1575552D03*
X525630Y1586575D03*
X534292Y1590906D03*
X525630Y1601930D03*
X534292Y1606260D03*
X525630Y1617284D03*
X534292Y1621615D03*
X629567Y1453504D03*
X638228Y1457835D03*
X629567Y1468859D03*
X638228Y1473189D03*
X629567Y1484213D03*
X638228Y1488544D03*
X629567Y1499567D03*
X638228Y1503898D03*
X629567Y1514922D03*
X638228Y1519252D03*
X629567Y1555867D03*
X638228Y1560197D03*
X629567Y1571221D03*
X638228Y1575552D03*
X629567Y1586575D03*
X638228Y1590906D03*
X629567Y1601930D03*
X638228Y1606260D03*
X629567Y1617284D03*
X638228Y1621615D03*
X646890Y1453504D03*
Y1468859D03*
Y1484213D03*
Y1499567D03*
Y1514922D03*
Y1555867D03*
Y1571221D03*
Y1586575D03*
Y1601930D03*
Y1617284D03*
X664213Y1453504D03*
X655551Y1457835D03*
X664213Y1468859D03*
X655551Y1473189D03*
X664213Y1484213D03*
X655551Y1488544D03*
X664213Y1499567D03*
Y1514922D03*
X655551Y1503898D03*
Y1519252D03*
X664213Y1555867D03*
X655551Y1560197D03*
X664213Y1571221D03*
X655551Y1575552D03*
X664213Y1586575D03*
X655551Y1590906D03*
X664213Y1601930D03*
X655551Y1606260D03*
X664213Y1617284D03*
X655551Y1621615D03*
X681535Y1453504D03*
X672874Y1457835D03*
X681535Y1468859D03*
X672874Y1473189D03*
X681535Y1484213D03*
X672874Y1488544D03*
X681535Y1499567D03*
Y1514922D03*
X672874Y1503898D03*
Y1519252D03*
X681535Y1555867D03*
X672874Y1560197D03*
X681535Y1571221D03*
X672874Y1575552D03*
X681535Y1586575D03*
X672874Y1590906D03*
X681535Y1601930D03*
X672874Y1606260D03*
X681535Y1617284D03*
X672874Y1621615D03*
X698858Y1453504D03*
X690197Y1457835D03*
X698858Y1468859D03*
X690197Y1473189D03*
X698858Y1484213D03*
X690197Y1488544D03*
X698858Y1499567D03*
Y1514922D03*
X690197Y1503898D03*
Y1519252D03*
X698858Y1555867D03*
X690197Y1560197D03*
X698858Y1571221D03*
X690197Y1575552D03*
X698858Y1586575D03*
X690197Y1590906D03*
X698858Y1601930D03*
X690197Y1606260D03*
X698858Y1617284D03*
X690197Y1621615D03*
X707520Y1457835D03*
Y1473189D03*
Y1488544D03*
Y1503898D03*
Y1519252D03*
Y1560197D03*
Y1575552D03*
Y1590906D03*
Y1606260D03*
Y1621615D03*
X1131850Y1453504D03*
X1140511Y1457835D03*
X1131850Y1468859D03*
X1140511Y1473189D03*
X1131850Y1484213D03*
X1140511Y1488544D03*
X1131850Y1499567D03*
X1140511Y1503898D03*
X1131850Y1514922D03*
X1140511Y1519252D03*
X1131850Y1555867D03*
X1140511Y1560197D03*
X1131850Y1571221D03*
X1140511Y1575552D03*
X1131850Y1586575D03*
X1140511Y1590906D03*
X1131850Y1601930D03*
X1140511Y1606260D03*
X1131850Y1617284D03*
X1140511Y1621615D03*
X1149173Y1453504D03*
X1157834Y1457835D03*
X1149173Y1468859D03*
X1157834Y1473189D03*
X1149173Y1484213D03*
X1157834Y1488544D03*
X1149173Y1499567D03*
X1157834Y1503898D03*
X1149173Y1514922D03*
X1157834Y1519252D03*
X1149173Y1555867D03*
X1157834Y1560197D03*
X1149173Y1571221D03*
X1157834Y1575552D03*
X1149173Y1586575D03*
X1157834Y1590906D03*
X1149173Y1601930D03*
X1157834Y1606260D03*
X1149173Y1617284D03*
X1157834Y1621615D03*
X1166496Y1453504D03*
Y1468859D03*
Y1484213D03*
Y1499567D03*
Y1514922D03*
Y1555867D03*
Y1571221D03*
Y1586575D03*
Y1601930D03*
Y1617284D03*
X1183818Y1453504D03*
X1175157Y1457835D03*
X1183818Y1468859D03*
X1175157Y1473189D03*
X1183818Y1484213D03*
X1175157Y1488544D03*
X1183818Y1499567D03*
Y1514922D03*
X1175157Y1503898D03*
Y1519252D03*
X1183818Y1555867D03*
X1175157Y1560197D03*
X1183818Y1571221D03*
X1175157Y1575552D03*
X1183818Y1586575D03*
X1175157Y1590906D03*
X1183818Y1601930D03*
X1175157Y1606260D03*
X1183818Y1617284D03*
X1175157Y1621615D03*
X1201141Y1453504D03*
X1192480Y1457835D03*
X1201141Y1468859D03*
X1192480Y1473189D03*
X1201141Y1484213D03*
X1192480Y1488544D03*
X1201141Y1499567D03*
Y1514922D03*
X1192480Y1503898D03*
Y1519252D03*
X1201141Y1555867D03*
X1192480Y1560197D03*
X1201141Y1571221D03*
X1192480Y1575552D03*
X1201141Y1586575D03*
X1192480Y1590906D03*
X1201141Y1601930D03*
X1192480Y1606260D03*
X1201141Y1617284D03*
X1192480Y1621615D03*
X1209803Y1457835D03*
Y1473189D03*
Y1488544D03*
Y1503898D03*
Y1519252D03*
Y1560197D03*
Y1575552D03*
Y1590906D03*
Y1606260D03*
Y1621615D03*
X1305079Y1453504D03*
X1313740Y1457835D03*
X1305079Y1468859D03*
X1313740Y1473189D03*
X1305079Y1484213D03*
X1313740Y1488544D03*
X1305079Y1499567D03*
X1313740Y1503898D03*
X1305079Y1514922D03*
X1313740Y1519252D03*
X1305079Y1555867D03*
X1313740Y1560197D03*
X1305079Y1571221D03*
X1313740Y1575552D03*
X1305079Y1586575D03*
X1313740Y1590906D03*
X1305079Y1601930D03*
X1313740Y1606260D03*
X1305079Y1617284D03*
X1313740Y1621615D03*
X1322402Y1453504D03*
X1331063Y1457835D03*
X1322402Y1468859D03*
X1331063Y1473189D03*
X1322402Y1484213D03*
X1331063Y1488544D03*
X1322402Y1499567D03*
X1331063Y1503898D03*
X1322402Y1514922D03*
X1331063Y1519252D03*
X1322402Y1555867D03*
X1331063Y1560197D03*
X1322402Y1571221D03*
X1331063Y1575552D03*
X1322402Y1586575D03*
X1331063Y1590906D03*
X1322402Y1601930D03*
X1331063Y1606260D03*
X1322402Y1617284D03*
X1331063Y1621615D03*
X1339725Y1453504D03*
X1348386Y1457835D03*
X1339725Y1468859D03*
X1348386Y1473189D03*
X1339725Y1484213D03*
X1348386Y1488544D03*
X1339725Y1499567D03*
X1348386Y1503898D03*
X1339725Y1514922D03*
X1348386Y1519252D03*
X1339725Y1555867D03*
X1348386Y1560197D03*
X1339725Y1571221D03*
X1348386Y1575552D03*
X1339725Y1586575D03*
X1348386Y1590906D03*
X1339725Y1601930D03*
X1348386Y1606260D03*
X1339725Y1617284D03*
X1348386Y1621615D03*
X1357047Y1453504D03*
X1365709Y1457835D03*
X1357047Y1468859D03*
X1365709Y1473189D03*
X1357047Y1484213D03*
X1365709Y1488544D03*
X1357047Y1499567D03*
X1365709Y1503898D03*
X1357047Y1514922D03*
X1365709Y1519252D03*
X1357047Y1555867D03*
X1365709Y1560197D03*
X1357047Y1571221D03*
X1365709Y1575552D03*
X1357047Y1586575D03*
X1365709Y1590906D03*
X1357047Y1601930D03*
X1365709Y1606260D03*
X1357047Y1617284D03*
X1365709Y1621615D03*
X1374370Y1453504D03*
X1383032Y1457835D03*
X1374370Y1468859D03*
X1383032Y1473189D03*
X1374370Y1484213D03*
X1383032Y1488544D03*
X1374370Y1499567D03*
X1383032Y1503898D03*
X1374370Y1514922D03*
X1383032Y1519252D03*
X1374370Y1555867D03*
X1383032Y1560197D03*
X1374370Y1571221D03*
X1383032Y1575552D03*
X1374370Y1586575D03*
X1383032Y1590906D03*
X1374370Y1601930D03*
X1383032Y1606260D03*
X1374370Y1617284D03*
X1383032Y1621615D03*
X1478307Y1453504D03*
Y1468859D03*
Y1484213D03*
Y1499567D03*
Y1514922D03*
Y1555867D03*
Y1571221D03*
Y1586575D03*
Y1601930D03*
Y1617284D03*
X1495630Y1453504D03*
X1486968Y1457835D03*
X1495630Y1468859D03*
X1486968Y1473189D03*
X1495630Y1484213D03*
X1486968Y1488544D03*
X1495630Y1499567D03*
Y1514922D03*
X1486968Y1503898D03*
Y1519252D03*
X1495630Y1555867D03*
X1486968Y1560197D03*
X1495630Y1571221D03*
X1486968Y1575552D03*
X1495630Y1586575D03*
X1486968Y1590906D03*
X1495630Y1601930D03*
X1486968Y1606260D03*
X1495630Y1617284D03*
X1486968Y1621615D03*
X1512953Y1453504D03*
X1504291Y1457835D03*
X1512953Y1468859D03*
X1504291Y1473189D03*
X1512953Y1484213D03*
X1504291Y1488544D03*
X1512953Y1499567D03*
Y1514922D03*
X1504291Y1503898D03*
Y1519252D03*
X1512953Y1555867D03*
X1504291Y1560197D03*
X1512953Y1571221D03*
X1504291Y1575552D03*
X1512953Y1586575D03*
X1504291Y1590906D03*
X1512953Y1601930D03*
X1504291Y1606260D03*
X1512953Y1617284D03*
X1504291Y1621615D03*
X1530275Y1453504D03*
X1521614Y1457835D03*
X1530275Y1468859D03*
X1521614Y1473189D03*
X1530275Y1484213D03*
X1521614Y1488544D03*
X1530275Y1499567D03*
Y1514922D03*
X1521614Y1503898D03*
Y1519252D03*
X1530275Y1555867D03*
X1521614Y1560197D03*
X1530275Y1571221D03*
X1521614Y1575552D03*
X1530275Y1586575D03*
X1521614Y1590906D03*
X1530275Y1601930D03*
X1521614Y1606260D03*
X1530275Y1617284D03*
X1521614Y1621615D03*
X1547598Y1453504D03*
X1538937Y1457835D03*
X1547598Y1468859D03*
X1538937Y1473189D03*
X1547598Y1484213D03*
X1538937Y1488544D03*
X1547598Y1499567D03*
Y1514922D03*
X1538937Y1503898D03*
Y1519252D03*
X1547598Y1555867D03*
X1538937Y1560197D03*
X1547598Y1571221D03*
X1538937Y1575552D03*
X1547598Y1586575D03*
X1538937Y1590906D03*
X1547598Y1601930D03*
X1538937Y1606260D03*
X1547598Y1617284D03*
X1538937Y1621615D03*
X1556260Y1457835D03*
Y1473189D03*
Y1488544D03*
Y1503898D03*
Y1519252D03*
Y1560197D03*
Y1575552D03*
Y1590906D03*
Y1606260D03*
Y1621615D03*
X1651535Y1453504D03*
X1660196Y1457835D03*
X1651535Y1468859D03*
X1660196Y1473189D03*
X1651535Y1484213D03*
X1660196Y1488544D03*
X1651535Y1499567D03*
X1660196Y1503898D03*
X1651535Y1514922D03*
X1660196Y1519252D03*
X1651535Y1555867D03*
X1660196Y1560197D03*
X1651535Y1571221D03*
X1660196Y1575552D03*
X1651535Y1586575D03*
X1660196Y1590906D03*
X1651535Y1601930D03*
X1660196Y1606260D03*
X1651535Y1617284D03*
X1660196Y1621615D03*
X1668858Y1453504D03*
X1677519Y1457835D03*
X1668858Y1468859D03*
X1677519Y1473189D03*
X1668858Y1484213D03*
X1677519Y1488544D03*
X1668858Y1499567D03*
X1677519Y1503898D03*
X1668858Y1514922D03*
X1677519Y1519252D03*
X1668858Y1555867D03*
X1677519Y1560197D03*
X1668858Y1571221D03*
X1677519Y1575552D03*
X1668858Y1586575D03*
X1677519Y1590906D03*
X1668858Y1601930D03*
X1677519Y1606260D03*
X1668858Y1617284D03*
X1677519Y1621615D03*
X1686181Y1453504D03*
Y1468859D03*
Y1484213D03*
Y1499567D03*
Y1514922D03*
Y1555867D03*
Y1571221D03*
Y1586575D03*
Y1601930D03*
Y1617284D03*
X1703503Y1453504D03*
X1694842Y1457835D03*
X1703503Y1468859D03*
X1694842Y1473189D03*
X1703503Y1484213D03*
X1694842Y1488544D03*
X1703503Y1499567D03*
Y1514922D03*
X1694842Y1503898D03*
Y1519252D03*
X1703503Y1555867D03*
X1694842Y1560197D03*
X1703503Y1571221D03*
X1694842Y1575552D03*
X1703503Y1586575D03*
X1694842Y1590906D03*
X1703503Y1601930D03*
X1694842Y1606260D03*
X1703503Y1617284D03*
X1694842Y1621615D03*
X1720826Y1453504D03*
X1712165Y1457835D03*
X1720826Y1468859D03*
X1712165Y1473189D03*
X1720826Y1484213D03*
X1712165Y1488544D03*
X1720826Y1499567D03*
Y1514922D03*
X1712165Y1503898D03*
Y1519252D03*
X1720826Y1555867D03*
X1712165Y1560197D03*
X1720826Y1571221D03*
X1712165Y1575552D03*
X1720826Y1586575D03*
X1712165Y1590906D03*
X1720826Y1601930D03*
X1712165Y1606260D03*
X1720826Y1617284D03*
X1712165Y1621615D03*
X1729488Y1457835D03*
Y1473189D03*
Y1488544D03*
Y1503898D03*
Y1519252D03*
Y1560197D03*
Y1575552D03*
Y1590906D03*
Y1606260D03*
Y1621615D03*
G54D31*
X51043Y144095D03*
X57933Y66811D03*
X160295D03*
X153405Y144095D03*
X183435Y630650D03*
X190325Y374862D03*
X262657Y66811D03*
X255767Y144095D03*
X279360Y630650D03*
X286250Y374862D03*
X358129Y144095D03*
X365019Y66811D03*
X508130Y144095D03*
X515020Y66811D03*
X617382D03*
X610492Y144095D03*
X647411Y374862D03*
X640521Y630650D03*
X719744Y66811D03*
X712854Y144095D03*
X736446Y630650D03*
X743336Y374862D03*
X815216Y144095D03*
X822106Y66811D03*
X972106D03*
X965216Y144095D03*
X1074468Y66811D03*
X1067578Y144095D03*
X1104498Y374862D03*
X1097608Y630650D03*
X1169940Y144095D03*
X1176830Y66811D03*
X1200423Y374862D03*
X1193533Y630650D03*
X1272302Y144095D03*
X1279192Y66811D03*
X1429193D03*
X1422303Y144095D03*
X1531555Y66811D03*
X1524665Y144095D03*
X1561585Y374862D03*
X1554695Y630650D03*
X1627027Y144095D03*
X1633917Y66811D03*
X1657510Y374862D03*
X1650620Y630650D03*
X1736279Y66811D03*
X1729389Y144095D03*
G54D14*
X15424Y1041679D03*
X28810D03*
X37157D03*
X50543D03*
X437627Y1234726D03*
X451013D03*
X476336D03*
X489722D03*
X862114Y1050682D03*
X875500D03*
X897233D03*
X883847D03*
X926091D03*
X947824D03*
X939477D03*
X961210D03*
X1351801Y1234726D03*
X1365187D03*
X1390510D03*
X1403896D03*
X1770071Y1051168D03*
X1783457D03*
X1791804D03*
X1805190D03*
G54D23*
X28819Y81575D03*
X73307Y61614D03*
X131181Y81575D03*
X175669Y61614D03*
X233543Y81575D03*
X278032Y61614D03*
X335906Y81575D03*
X380394Y61614D03*
X485886Y81595D03*
X530394Y61614D03*
X588248Y81594D03*
X632756Y61614D03*
X690611Y81595D03*
X735118Y61614D03*
X792973Y81595D03*
X837480Y61614D03*
X942973Y81595D03*
X987480Y61614D03*
X1045335Y81595D03*
X1089843Y61614D03*
X1147697Y81595D03*
X1192205Y61614D03*
X1250060Y81595D03*
X1294567Y61614D03*
X1400060Y81595D03*
X1444567Y61614D03*
X1502441Y81575D03*
X1546929Y61614D03*
X1604784Y81595D03*
X1649291Y61614D03*
X1707146Y81595D03*
X1751654Y61614D03*
G54D32*
X44079Y1529376D03*
Y1536376D03*
X394175Y1399389D03*
Y1406389D03*
X410955Y318485D03*
Y325485D03*
X405121Y930778D03*
X397121D03*
X405121Y937778D03*
X397121D03*
X411095Y1102897D03*
Y1109897D03*
X405231Y1124747D03*
Y1117747D03*
X423750Y538080D03*
Y545080D03*
X413121Y930778D03*
X421121D03*
X413121Y937778D03*
X421121D03*
X413231Y1124747D03*
Y1117747D03*
X426934Y1198971D03*
Y1191971D03*
X413469Y1198971D03*
Y1191971D03*
X435804Y538090D03*
Y545090D03*
X443223Y1102897D03*
Y1109897D03*
X437359Y1124747D03*
Y1117747D03*
X432975Y1152039D03*
Y1159039D03*
X434266Y1378453D03*
Y1371453D03*
X459104Y537990D03*
X447614Y538080D03*
X459104Y544990D03*
X447614Y545080D03*
X445359Y1124747D03*
Y1117747D03*
X470818Y1124747D03*
Y1117747D03*
X476682Y1102897D03*
X478818Y1124747D03*
Y1117747D03*
X476682Y1109897D03*
X486671Y1198971D03*
Y1191971D03*
X508810Y1102897D03*
Y1109897D03*
X502946Y1124747D03*
Y1117747D03*
X498562Y1152039D03*
Y1159039D03*
X500136Y1198971D03*
Y1191971D03*
X510946Y1124747D03*
Y1117747D03*
X1313540Y321577D03*
Y328577D03*
X1319405Y1124747D03*
Y1117747D03*
X1325269Y1102897D03*
Y1109897D03*
X1327405Y1124747D03*
Y1117747D03*
X1327643Y1198971D03*
Y1191971D03*
X1351533Y1124747D03*
Y1117747D03*
X1347149Y1152039D03*
Y1159039D03*
X1341108Y1198971D03*
Y1191971D03*
X1357397Y1102897D03*
Y1109897D03*
X1359533Y1124747D03*
Y1117747D03*
X1384992Y1124747D03*
Y1117747D03*
X1390856Y1102897D03*
Y1109897D03*
X1392992Y1124747D03*
Y1117747D03*
X1400845Y1198971D03*
Y1191971D03*
X1417120Y1124747D03*
Y1117747D03*
X1412736Y1152039D03*
Y1159039D03*
X1414310Y1198971D03*
Y1191971D03*
X1422984Y1102897D03*
Y1109897D03*
X1425120Y1124747D03*
Y1117747D03*
G54D41*
X109882Y1458622D03*
Y1463741D03*
Y1473977D03*
Y1479095D03*
Y1489331D03*
Y1494449D03*
Y1504685D03*
Y1509804D03*
Y1560985D03*
Y1566103D03*
Y1576339D03*
Y1581457D03*
Y1591693D03*
Y1596811D03*
Y1607048D03*
Y1612166D03*
X127205Y1458622D03*
Y1463741D03*
X118543Y1462953D03*
X127205Y1473977D03*
Y1479095D03*
X118543Y1468071D03*
Y1478308D03*
X127205Y1489331D03*
Y1494449D03*
X118543Y1483426D03*
Y1493662D03*
Y1498780D03*
X127205Y1504685D03*
Y1509804D03*
X118543Y1509016D03*
Y1514134D03*
X127205Y1560985D03*
Y1566103D03*
Y1576339D03*
X118543Y1565315D03*
Y1570434D03*
X127205Y1581457D03*
Y1591693D03*
X118543Y1580670D03*
Y1585788D03*
Y1596024D03*
X127205Y1596811D03*
Y1607048D03*
Y1612166D03*
X118543Y1601142D03*
Y1611378D03*
Y1616496D03*
X144528Y1458622D03*
Y1463741D03*
X135866Y1462953D03*
X144528Y1473977D03*
Y1479095D03*
X135866Y1468071D03*
Y1478308D03*
X144528Y1489331D03*
Y1494449D03*
X135866Y1483426D03*
Y1493662D03*
Y1498780D03*
X144528Y1504685D03*
Y1509804D03*
X135866Y1509016D03*
Y1514134D03*
X144528Y1560985D03*
Y1566103D03*
Y1576339D03*
X135866Y1565315D03*
Y1570434D03*
X144528Y1581457D03*
Y1591693D03*
X135866Y1580670D03*
Y1585788D03*
Y1596024D03*
X144528Y1596811D03*
Y1607048D03*
Y1612166D03*
X135866Y1601142D03*
Y1611378D03*
Y1616496D03*
X161850Y1458622D03*
Y1463741D03*
X153189Y1462953D03*
X161850Y1473977D03*
Y1479095D03*
X153189Y1468071D03*
Y1478308D03*
X161850Y1489331D03*
Y1494449D03*
X153189Y1483426D03*
Y1493662D03*
Y1498780D03*
X161850Y1504685D03*
Y1509804D03*
X153189Y1509016D03*
Y1514134D03*
X161850Y1560985D03*
Y1566103D03*
Y1576339D03*
X153189Y1565315D03*
Y1570434D03*
X161850Y1581457D03*
Y1591693D03*
X153189Y1580670D03*
Y1585788D03*
Y1596024D03*
X161850Y1596811D03*
Y1607048D03*
Y1612166D03*
X153189Y1601142D03*
Y1611378D03*
Y1616496D03*
X179173Y1458622D03*
Y1463741D03*
X170512Y1462953D03*
X179173Y1473977D03*
Y1479095D03*
X170512Y1468071D03*
Y1478308D03*
Y1483426D03*
Y1493662D03*
Y1498780D03*
Y1509016D03*
Y1514134D03*
Y1565315D03*
Y1570434D03*
Y1580670D03*
Y1585788D03*
Y1596024D03*
Y1601142D03*
Y1611378D03*
Y1616496D03*
X187835Y1462953D03*
Y1468071D03*
Y1478308D03*
Y1483426D03*
Y1596024D03*
Y1601142D03*
Y1611378D03*
Y1616496D03*
X283110Y1458622D03*
X291771Y1462953D03*
X283110Y1463741D03*
X291771Y1468071D03*
X283110Y1473977D03*
X291771Y1478308D03*
X283110Y1479095D03*
X291771Y1483426D03*
X283110Y1489331D03*
X291771Y1493662D03*
X283110Y1494449D03*
X291771Y1498780D03*
X283110Y1504685D03*
X291771Y1509016D03*
X283110Y1509804D03*
X291771Y1514134D03*
X283110Y1560985D03*
X291771Y1565315D03*
X283110Y1566103D03*
X291771Y1570434D03*
X283110Y1576339D03*
X291771Y1580670D03*
X283110Y1581457D03*
X291771Y1585788D03*
X283110Y1591693D03*
X291771Y1596024D03*
X283110Y1596811D03*
X291771Y1601142D03*
X283110Y1607048D03*
X291771Y1611378D03*
X283110Y1612166D03*
X291771Y1616496D03*
X300433Y1458622D03*
X309094Y1462953D03*
X300433Y1463741D03*
X309094Y1468071D03*
X300433Y1473977D03*
X309094Y1478308D03*
X300433Y1479095D03*
X309094Y1483426D03*
X300433Y1489331D03*
X309094Y1493662D03*
X300433Y1494449D03*
X309094Y1498780D03*
X300433Y1504685D03*
X309094Y1509016D03*
X300433Y1509804D03*
X309094Y1514134D03*
X300433Y1560985D03*
X309094Y1565315D03*
X300433Y1566103D03*
X309094Y1570434D03*
X300433Y1576339D03*
X309094Y1580670D03*
X300433Y1581457D03*
X309094Y1585788D03*
X300433Y1591693D03*
X309094Y1596024D03*
X300433Y1596811D03*
X309094Y1601142D03*
X300433Y1607048D03*
X309094Y1611378D03*
X300433Y1612166D03*
X309094Y1616496D03*
X317756Y1458622D03*
X326417Y1462953D03*
X317756Y1463741D03*
X326417Y1468071D03*
X317756Y1473977D03*
X326417Y1478308D03*
X317756Y1479095D03*
X326417Y1483426D03*
X317756Y1489331D03*
X326417Y1493662D03*
X317756Y1494449D03*
X326417Y1498780D03*
X317756Y1504685D03*
X326417Y1509016D03*
X317756Y1509804D03*
X326417Y1514134D03*
X317756Y1560985D03*
X326417Y1565315D03*
X317756Y1566103D03*
X326417Y1570434D03*
X317756Y1576339D03*
X326417Y1580670D03*
X317756Y1581457D03*
X326417Y1585788D03*
X317756Y1591693D03*
X326417Y1596024D03*
X317756Y1596811D03*
X326417Y1601142D03*
X317756Y1607048D03*
X326417Y1611378D03*
X317756Y1612166D03*
X326417Y1616496D03*
X335078Y1458622D03*
X343740Y1462953D03*
X335078Y1463741D03*
X343740Y1468071D03*
X335078Y1473977D03*
X343740Y1478308D03*
X335078Y1479095D03*
X343740Y1483426D03*
X335078Y1489331D03*
X343740Y1493662D03*
X335078Y1494449D03*
X343740Y1498780D03*
X335078Y1504685D03*
X343740Y1509016D03*
X335078Y1509804D03*
X343740Y1514134D03*
X335078Y1560985D03*
X343740Y1565315D03*
X335078Y1566103D03*
X343740Y1570434D03*
X335078Y1576339D03*
X343740Y1580670D03*
X335078Y1581457D03*
X343740Y1585788D03*
X335078Y1591693D03*
X343740Y1596024D03*
X335078Y1596811D03*
X343740Y1601142D03*
X335078Y1607048D03*
X343740Y1611378D03*
X335078Y1612166D03*
X343740Y1616496D03*
X361063Y1596024D03*
Y1601142D03*
Y1611378D03*
Y1616496D03*
X456339Y1458622D03*
Y1463741D03*
Y1473977D03*
Y1479095D03*
Y1489331D03*
Y1494449D03*
Y1504685D03*
Y1509804D03*
Y1560985D03*
Y1566103D03*
Y1576339D03*
Y1581457D03*
Y1591693D03*
Y1596811D03*
Y1607048D03*
Y1612166D03*
X473662Y1458622D03*
Y1463741D03*
X465000Y1462953D03*
X473662Y1473977D03*
Y1479095D03*
X465000Y1468071D03*
Y1478308D03*
X473662Y1489331D03*
Y1494449D03*
X465000Y1483426D03*
Y1493662D03*
Y1498780D03*
X473662Y1504685D03*
Y1509804D03*
X465000Y1509016D03*
Y1514134D03*
X473662Y1560985D03*
Y1566103D03*
Y1576339D03*
X465000Y1565315D03*
Y1570434D03*
X473662Y1581457D03*
Y1591693D03*
X465000Y1580670D03*
Y1585788D03*
Y1596024D03*
X473662Y1596811D03*
Y1607048D03*
Y1612166D03*
X465000Y1601142D03*
Y1611378D03*
Y1616496D03*
X490985Y1458622D03*
Y1463741D03*
X482323Y1462953D03*
X490985Y1473977D03*
Y1479095D03*
X482323Y1468071D03*
Y1478308D03*
X490985Y1489331D03*
Y1494449D03*
X482323Y1483426D03*
Y1493662D03*
Y1498780D03*
X490985Y1504685D03*
Y1509804D03*
X482323Y1509016D03*
Y1514134D03*
X490985Y1560985D03*
Y1566103D03*
Y1576339D03*
X482323Y1565315D03*
Y1570434D03*
X490985Y1581457D03*
Y1591693D03*
X482323Y1580670D03*
Y1585788D03*
Y1596024D03*
X490985Y1596811D03*
Y1607048D03*
Y1612166D03*
X482323Y1601142D03*
Y1611378D03*
Y1616496D03*
X499646Y1462953D03*
Y1468071D03*
Y1478308D03*
Y1483426D03*
Y1493662D03*
Y1498780D03*
Y1509016D03*
Y1514134D03*
Y1565315D03*
Y1570434D03*
Y1580670D03*
Y1585788D03*
Y1596024D03*
Y1601142D03*
Y1611378D03*
Y1616496D03*
X508307Y1458622D03*
X516969Y1462953D03*
X508307Y1463741D03*
X516969Y1468071D03*
X508307Y1473977D03*
X516969Y1478308D03*
X508307Y1479095D03*
X516969Y1483426D03*
X508307Y1489331D03*
X516969Y1493662D03*
X508307Y1494449D03*
X516969Y1498780D03*
X508307Y1504685D03*
X516969Y1509016D03*
X508307Y1509804D03*
X516969Y1514134D03*
X508307Y1560985D03*
X516969Y1565315D03*
X508307Y1566103D03*
X516969Y1570434D03*
X508307Y1576339D03*
X516969Y1580670D03*
X508307Y1581457D03*
X516969Y1585788D03*
X508307Y1591693D03*
X516969Y1596024D03*
X508307Y1596811D03*
X516969Y1601142D03*
X508307Y1607048D03*
X516969Y1611378D03*
X508307Y1612166D03*
X516969Y1616496D03*
X629567Y1458622D03*
Y1463741D03*
Y1473977D03*
Y1479095D03*
Y1489331D03*
Y1494449D03*
Y1504685D03*
Y1509804D03*
Y1560985D03*
Y1566103D03*
Y1576339D03*
Y1581457D03*
Y1591693D03*
Y1596811D03*
Y1607048D03*
Y1612166D03*
X646890Y1458622D03*
Y1463741D03*
X638228Y1462953D03*
X646890Y1473977D03*
Y1479095D03*
X638228Y1468071D03*
Y1478308D03*
X646890Y1489331D03*
Y1494449D03*
X638228Y1483426D03*
Y1493662D03*
Y1498780D03*
X646890Y1504685D03*
Y1509804D03*
X638228Y1509016D03*
Y1514134D03*
X646890Y1560985D03*
Y1566103D03*
Y1576339D03*
X638228Y1565315D03*
Y1570434D03*
X646890Y1581457D03*
Y1591693D03*
X638228Y1580670D03*
Y1585788D03*
Y1596024D03*
X646890Y1596811D03*
Y1607048D03*
Y1612166D03*
X638228Y1601142D03*
Y1611378D03*
Y1616496D03*
X664213Y1458622D03*
Y1463741D03*
X655551Y1462953D03*
X664213Y1473977D03*
Y1479095D03*
X655551Y1468071D03*
Y1478308D03*
X664213Y1489331D03*
Y1494449D03*
X655551Y1483426D03*
Y1493662D03*
Y1498780D03*
X664213Y1504685D03*
Y1509804D03*
X655551Y1509016D03*
Y1514134D03*
X664213Y1560985D03*
Y1566103D03*
Y1576339D03*
X655551Y1565315D03*
Y1570434D03*
X664213Y1581457D03*
Y1591693D03*
X655551Y1580670D03*
Y1585788D03*
Y1596024D03*
X664213Y1596811D03*
Y1607048D03*
Y1612166D03*
X655551Y1601142D03*
Y1611378D03*
Y1616496D03*
X681535Y1458622D03*
Y1463741D03*
X672874Y1462953D03*
X681535Y1473977D03*
Y1479095D03*
X672874Y1468071D03*
Y1478308D03*
X681535Y1489331D03*
Y1494449D03*
X672874Y1483426D03*
Y1493662D03*
Y1498780D03*
X681535Y1504685D03*
Y1509804D03*
X672874Y1509016D03*
Y1514134D03*
X681535Y1560985D03*
Y1566103D03*
Y1576339D03*
X672874Y1565315D03*
Y1570434D03*
X681535Y1581457D03*
Y1591693D03*
X672874Y1580670D03*
Y1585788D03*
Y1596024D03*
X681535Y1596811D03*
Y1607048D03*
Y1612166D03*
X672874Y1601142D03*
Y1611378D03*
Y1616496D03*
X690197Y1462953D03*
Y1468071D03*
Y1478308D03*
Y1483426D03*
Y1493662D03*
Y1498780D03*
Y1509016D03*
Y1514134D03*
Y1565315D03*
Y1570434D03*
Y1580670D03*
Y1585788D03*
Y1596024D03*
Y1601142D03*
Y1611378D03*
Y1616496D03*
X1131850Y1458622D03*
X1140511Y1462953D03*
X1131850Y1463741D03*
X1140511Y1468071D03*
X1131850Y1473977D03*
X1140511Y1478308D03*
X1131850Y1479095D03*
X1140511Y1483426D03*
X1131850Y1489331D03*
X1140511Y1493662D03*
X1131850Y1494449D03*
X1140511Y1498780D03*
X1131850Y1504685D03*
X1140511Y1509016D03*
X1131850Y1509804D03*
X1140511Y1514134D03*
X1131850Y1560985D03*
X1140511Y1565315D03*
X1131850Y1566103D03*
X1140511Y1570434D03*
X1131850Y1576339D03*
X1140511Y1580670D03*
X1131850Y1581457D03*
X1140511Y1585788D03*
X1131850Y1591693D03*
X1140511Y1596024D03*
X1131850Y1596811D03*
X1140511Y1601142D03*
X1131850Y1607048D03*
X1140511Y1611378D03*
X1131850Y1612166D03*
X1140511Y1616496D03*
X1149173Y1458622D03*
Y1463741D03*
Y1473977D03*
Y1479095D03*
Y1489331D03*
Y1494449D03*
Y1504685D03*
Y1509804D03*
Y1560985D03*
Y1566103D03*
Y1576339D03*
Y1581457D03*
Y1591693D03*
Y1596811D03*
Y1607048D03*
Y1612166D03*
X1166496Y1458622D03*
Y1463741D03*
X1157834Y1462953D03*
X1166496Y1473977D03*
Y1479095D03*
X1157834Y1468071D03*
Y1478308D03*
X1166496Y1489331D03*
Y1494449D03*
X1157834Y1483426D03*
Y1493662D03*
Y1498780D03*
X1166496Y1504685D03*
Y1509804D03*
X1157834Y1509016D03*
Y1514134D03*
X1166496Y1560985D03*
Y1566103D03*
Y1576339D03*
X1157834Y1565315D03*
Y1570434D03*
X1166496Y1581457D03*
Y1591693D03*
X1157834Y1580670D03*
Y1585788D03*
Y1596024D03*
X1166496Y1596811D03*
Y1607048D03*
Y1612166D03*
X1157834Y1601142D03*
Y1611378D03*
Y1616496D03*
X1183818Y1458622D03*
Y1463741D03*
X1175157Y1462953D03*
X1183818Y1473977D03*
Y1479095D03*
X1175157Y1468071D03*
Y1478308D03*
X1183818Y1489331D03*
Y1494449D03*
X1175157Y1483426D03*
Y1493662D03*
Y1498780D03*
X1183818Y1504685D03*
Y1509804D03*
X1175157Y1509016D03*
Y1514134D03*
X1183818Y1560985D03*
Y1566103D03*
Y1576339D03*
X1175157Y1565315D03*
Y1570434D03*
X1183818Y1581457D03*
Y1591693D03*
X1175157Y1580670D03*
Y1585788D03*
Y1596024D03*
X1183818Y1596811D03*
Y1607048D03*
Y1612166D03*
X1175157Y1601142D03*
Y1611378D03*
Y1616496D03*
X1192480Y1462953D03*
Y1468071D03*
Y1478308D03*
Y1483426D03*
Y1493662D03*
Y1498780D03*
Y1509016D03*
Y1514134D03*
Y1565315D03*
Y1570434D03*
Y1580670D03*
Y1585788D03*
Y1596024D03*
Y1601142D03*
Y1611378D03*
Y1616496D03*
X1305079Y1458622D03*
X1313740Y1462953D03*
X1305079Y1463741D03*
X1313740Y1468071D03*
X1305079Y1473977D03*
X1313740Y1478308D03*
X1305079Y1479095D03*
X1313740Y1483426D03*
X1305079Y1489331D03*
X1313740Y1493662D03*
X1305079Y1494449D03*
X1313740Y1498780D03*
X1305079Y1504685D03*
X1313740Y1509016D03*
X1305079Y1509804D03*
X1313740Y1514134D03*
X1305079Y1560985D03*
X1313740Y1565315D03*
X1305079Y1566103D03*
X1313740Y1570434D03*
X1305079Y1576339D03*
X1313740Y1580670D03*
X1305079Y1581457D03*
X1313740Y1585788D03*
X1305079Y1591693D03*
X1313740Y1596024D03*
X1305079Y1596811D03*
X1313740Y1601142D03*
X1305079Y1607048D03*
X1313740Y1611378D03*
X1305079Y1612166D03*
X1313740Y1616496D03*
X1322402Y1458622D03*
X1331063Y1462953D03*
X1322402Y1463741D03*
X1331063Y1468071D03*
X1322402Y1473977D03*
X1331063Y1478308D03*
X1322402Y1479095D03*
X1331063Y1483426D03*
X1322402Y1489331D03*
X1331063Y1493662D03*
X1322402Y1494449D03*
X1331063Y1498780D03*
X1322402Y1504685D03*
X1331063Y1509016D03*
X1322402Y1509804D03*
X1331063Y1514134D03*
X1322402Y1560985D03*
X1331063Y1565315D03*
X1322402Y1566103D03*
X1331063Y1570434D03*
X1322402Y1576339D03*
X1331063Y1580670D03*
X1322402Y1581457D03*
X1331063Y1585788D03*
X1322402Y1591693D03*
X1331063Y1596024D03*
X1322402Y1596811D03*
X1331063Y1601142D03*
X1322402Y1607048D03*
X1331063Y1611378D03*
X1322402Y1612166D03*
X1331063Y1616496D03*
X1339725Y1458622D03*
X1348386Y1462953D03*
X1339725Y1463741D03*
X1348386Y1468071D03*
X1339725Y1473977D03*
X1348386Y1478308D03*
X1339725Y1479095D03*
X1348386Y1483426D03*
X1339725Y1489331D03*
X1348386Y1493662D03*
X1339725Y1494449D03*
X1348386Y1498780D03*
X1339725Y1504685D03*
X1348386Y1509016D03*
X1339725Y1509804D03*
X1348386Y1514134D03*
X1339725Y1560985D03*
X1348386Y1565315D03*
X1339725Y1566103D03*
X1348386Y1570434D03*
X1339725Y1576339D03*
X1348386Y1580670D03*
X1339725Y1581457D03*
X1348386Y1585788D03*
X1339725Y1591693D03*
X1348386Y1596024D03*
X1339725Y1596811D03*
X1348386Y1601142D03*
X1339725Y1607048D03*
X1348386Y1611378D03*
X1339725Y1612166D03*
X1348386Y1616496D03*
X1357047Y1458622D03*
X1365709Y1462953D03*
X1357047Y1463741D03*
X1365709Y1468071D03*
X1357047Y1473977D03*
X1365709Y1478308D03*
X1357047Y1479095D03*
X1365709Y1483426D03*
X1357047Y1489331D03*
X1365709Y1493662D03*
X1357047Y1494449D03*
X1365709Y1498780D03*
X1357047Y1504685D03*
X1365709Y1509016D03*
X1357047Y1509804D03*
X1365709Y1514134D03*
X1357047Y1560985D03*
X1365709Y1565315D03*
X1357047Y1566103D03*
X1365709Y1570434D03*
X1357047Y1576339D03*
X1365709Y1580670D03*
X1357047Y1581457D03*
X1365709Y1585788D03*
X1357047Y1591693D03*
X1365709Y1596024D03*
X1357047Y1596811D03*
X1365709Y1601142D03*
X1357047Y1607048D03*
X1365709Y1611378D03*
X1357047Y1612166D03*
X1365709Y1616496D03*
X1478307Y1458622D03*
Y1463741D03*
Y1473977D03*
Y1479095D03*
Y1489331D03*
Y1494449D03*
Y1504685D03*
Y1509804D03*
Y1560985D03*
Y1566103D03*
Y1576339D03*
Y1581457D03*
Y1591693D03*
Y1596811D03*
Y1607048D03*
Y1612166D03*
X1495630Y1458622D03*
Y1463741D03*
X1486968Y1462953D03*
X1495630Y1473977D03*
Y1479095D03*
X1486968Y1468071D03*
Y1478308D03*
X1495630Y1489331D03*
Y1494449D03*
X1486968Y1483426D03*
Y1493662D03*
Y1498780D03*
X1495630Y1504685D03*
Y1509804D03*
X1486968Y1509016D03*
Y1514134D03*
X1495630Y1560985D03*
Y1566103D03*
Y1576339D03*
X1486968Y1565315D03*
Y1570434D03*
X1495630Y1581457D03*
Y1591693D03*
X1486968Y1580670D03*
Y1585788D03*
Y1596024D03*
X1495630Y1596811D03*
Y1607048D03*
Y1612166D03*
X1486968Y1601142D03*
Y1611378D03*
Y1616496D03*
X1512953Y1458622D03*
Y1463741D03*
X1504291Y1462953D03*
X1512953Y1473977D03*
Y1479095D03*
X1504291Y1468071D03*
Y1478308D03*
X1512953Y1489331D03*
Y1494449D03*
X1504291Y1483426D03*
Y1493662D03*
Y1498780D03*
X1512953Y1504685D03*
Y1509804D03*
X1504291Y1509016D03*
Y1514134D03*
X1512953Y1560985D03*
Y1566103D03*
Y1576339D03*
X1504291Y1565315D03*
Y1570434D03*
X1512953Y1581457D03*
Y1591693D03*
X1504291Y1580670D03*
Y1585788D03*
Y1596024D03*
X1512953Y1596811D03*
Y1607048D03*
Y1612166D03*
X1504291Y1601142D03*
Y1611378D03*
Y1616496D03*
X1530275Y1458622D03*
Y1463741D03*
X1521614Y1462953D03*
X1530275Y1473977D03*
Y1479095D03*
X1521614Y1468071D03*
Y1478308D03*
X1530275Y1489331D03*
Y1494449D03*
X1521614Y1483426D03*
Y1493662D03*
Y1498780D03*
X1530275Y1504685D03*
Y1509804D03*
X1521614Y1509016D03*
Y1514134D03*
X1530275Y1560985D03*
Y1566103D03*
Y1576339D03*
X1521614Y1565315D03*
Y1570434D03*
X1530275Y1581457D03*
Y1591693D03*
X1521614Y1580670D03*
Y1585788D03*
Y1596024D03*
X1530275Y1596811D03*
Y1607048D03*
Y1612166D03*
X1521614Y1601142D03*
Y1611378D03*
Y1616496D03*
X1538937Y1462953D03*
Y1468071D03*
Y1478308D03*
Y1483426D03*
Y1493662D03*
Y1498780D03*
Y1509016D03*
Y1514134D03*
Y1565315D03*
Y1570434D03*
Y1580670D03*
Y1585788D03*
Y1596024D03*
Y1601142D03*
Y1611378D03*
Y1616496D03*
X1651535Y1458622D03*
X1660196Y1462953D03*
X1651535Y1463741D03*
X1660196Y1468071D03*
X1651535Y1473977D03*
X1660196Y1478308D03*
X1651535Y1479095D03*
X1660196Y1483426D03*
X1651535Y1489331D03*
X1660196Y1493662D03*
X1651535Y1494449D03*
X1660196Y1498780D03*
X1651535Y1504685D03*
X1660196Y1509016D03*
X1651535Y1509804D03*
X1660196Y1514134D03*
X1651535Y1560985D03*
X1660196Y1565315D03*
X1651535Y1566103D03*
X1660196Y1570434D03*
X1651535Y1576339D03*
X1660196Y1580670D03*
X1651535Y1581457D03*
X1660196Y1585788D03*
X1651535Y1591693D03*
X1660196Y1596024D03*
X1651535Y1596811D03*
X1660196Y1601142D03*
X1651535Y1607048D03*
X1660196Y1611378D03*
X1651535Y1612166D03*
X1660196Y1616496D03*
X1668858Y1458622D03*
Y1463741D03*
Y1473977D03*
Y1479095D03*
Y1489331D03*
Y1494449D03*
Y1504685D03*
Y1509804D03*
Y1560985D03*
Y1566103D03*
Y1576339D03*
Y1581457D03*
Y1591693D03*
Y1596811D03*
Y1607048D03*
Y1612166D03*
X1686181Y1458622D03*
Y1463741D03*
X1677519Y1462953D03*
X1686181Y1473977D03*
Y1479095D03*
X1677519Y1468071D03*
Y1478308D03*
X1686181Y1489331D03*
Y1494449D03*
X1677519Y1483426D03*
Y1493662D03*
Y1498780D03*
X1686181Y1504685D03*
Y1509804D03*
X1677519Y1509016D03*
Y1514134D03*
X1686181Y1560985D03*
Y1566103D03*
Y1576339D03*
X1677519Y1565315D03*
Y1570434D03*
X1686181Y1581457D03*
Y1591693D03*
X1677519Y1580670D03*
Y1585788D03*
Y1596024D03*
X1686181Y1596811D03*
Y1607048D03*
Y1612166D03*
X1677519Y1601142D03*
Y1611378D03*
Y1616496D03*
X1703503Y1458622D03*
Y1463741D03*
X1694842Y1462953D03*
X1703503Y1473977D03*
Y1479095D03*
X1694842Y1468071D03*
Y1478308D03*
X1703503Y1489331D03*
Y1494449D03*
X1694842Y1483426D03*
Y1493662D03*
Y1498780D03*
X1703503Y1504685D03*
Y1509804D03*
X1694842Y1509016D03*
Y1514134D03*
X1703503Y1560985D03*
Y1566103D03*
Y1576339D03*
X1694842Y1565315D03*
Y1570434D03*
X1703503Y1581457D03*
Y1591693D03*
X1694842Y1580670D03*
Y1585788D03*
Y1596024D03*
X1703503Y1596811D03*
Y1607048D03*
Y1612166D03*
X1694842Y1601142D03*
Y1611378D03*
Y1616496D03*
X1712165Y1462953D03*
Y1468071D03*
Y1478308D03*
Y1483426D03*
Y1493662D03*
Y1498780D03*
Y1509016D03*
Y1514134D03*
Y1565315D03*
Y1570434D03*
Y1580670D03*
Y1585788D03*
Y1596024D03*
Y1601142D03*
Y1611378D03*
Y1616496D03*
G54D50*
X208035Y1516515D03*
X1460832Y763285D03*
X1459752Y806881D03*
X1626782Y659526D03*
X1763546Y802817D03*
G54D24*
X34946Y1082645D03*
X35992Y1090694D03*
X33892D03*
X35936Y1093825D03*
X33836D03*
X42947Y1073034D03*
X40847D03*
X37046Y1082645D03*
X97906Y1021028D03*
X100006D03*
X97837Y1024139D03*
X99937D03*
X181618Y562188D03*
X179518D03*
X181618Y565388D03*
X179518D03*
X181618Y568588D03*
X179518D03*
X181618Y571988D03*
X179518D03*
X181618Y575388D03*
X179518D03*
X181430Y1144389D03*
X181450Y1151870D03*
Y1155610D03*
X173949Y1153740D03*
X176049D03*
X173949Y1149999D03*
X176049D03*
X181450Y1166830D03*
X173949Y1157480D03*
X176049D03*
X181450Y1159350D03*
Y1162450D03*
Y1170570D03*
X173949Y1161220D03*
X176049D03*
X173949Y1164960D03*
X176049D03*
X173949Y1174310D03*
X176049D03*
X181450Y1181800D03*
Y1178000D03*
X173949Y1178051D03*
X176049D03*
X173949Y1181791D03*
X176049D03*
X181450Y1185200D03*
X194750Y1136909D03*
X192650D03*
X194750Y1144389D03*
X192650D03*
X182950Y1148129D03*
X185050D03*
X194750Y1151869D03*
X192650D03*
Y1148129D03*
X194750D03*
X183530Y1144389D03*
X183550Y1151870D03*
Y1155610D03*
Y1166830D03*
X192830D03*
X194930D03*
X183550Y1159350D03*
Y1162450D03*
Y1170570D03*
X194550Y1185100D03*
X192450D03*
X182950Y1174310D03*
X185050D03*
X194750Y1178250D03*
X192650D03*
Y1181791D03*
X194750D03*
X183550Y1181800D03*
Y1178000D03*
Y1185200D03*
X195570Y1193011D03*
X193470D03*
X188090D03*
X190190D03*
X200311Y1166830D03*
X202411D03*
X207791D03*
X209891D03*
X230132D03*
X222752D03*
X224852D03*
X215271D03*
X217371D03*
X239050Y1166900D03*
X236950D03*
X241950D03*
X244050D03*
X232232Y1166830D03*
X248833D03*
X250933D03*
X256313D03*
X258413D03*
X270373Y1129429D03*
X272473D03*
X277034Y1140649D03*
X274934D03*
X277034Y1136909D03*
X274934D03*
X270373Y1133169D03*
X272473D03*
X277034Y1144389D03*
X274934D03*
X269553Y1155610D03*
X267453D03*
X278674D03*
X263713Y1166830D03*
X265813D03*
X278674Y1159350D03*
X273294D03*
X271194D03*
X273294Y1166830D03*
X271194D03*
X273294Y1170570D03*
X271194D03*
X278674Y1166830D03*
Y1170570D03*
X270373Y1178051D03*
X268273D03*
X271194Y1185531D03*
X273294D03*
X277854Y1181791D03*
X273294D03*
X271194D03*
X278674Y1174310D03*
X269553D03*
X267453D03*
X271194Y1189271D03*
X273294D03*
X271194Y1193011D03*
X273294D03*
X287927Y436924D03*
X290027D03*
X287927Y433524D03*
X290027D03*
X287927Y430124D03*
X290027D03*
X287927Y440124D03*
X290027D03*
X287927Y443324D03*
X290027D03*
X280774Y1155610D03*
X288254Y1157480D03*
X286154D03*
X288254Y1161220D03*
X286154D03*
X288254Y1168700D03*
X286154D03*
X288254Y1172440D03*
X286154D03*
X288254Y1164960D03*
X286154D03*
X280774Y1159350D03*
Y1166830D03*
Y1170570D03*
X279954Y1181791D03*
X285334D03*
X283234D03*
X280774Y1174310D03*
X460846Y1250700D03*
X458746D03*
X460846Y1254104D03*
X458746D03*
X460846Y1247512D03*
X458746D03*
X460846Y1244163D03*
X458746D03*
X465316Y1247512D03*
X467416D03*
X465316Y1254104D03*
X467416D03*
X465316Y1244109D03*
X467416D03*
X465316Y1250814D03*
X467416D03*
X636604Y562188D03*
Y565388D03*
Y568588D03*
Y571988D03*
Y575388D03*
X631036Y1149999D03*
X633136D03*
X631036Y1153740D03*
X633136D03*
X631036Y1157480D03*
X633136D03*
X631036Y1172500D03*
X633136D03*
X631036Y1161220D03*
X633136D03*
X631036Y1164960D03*
X633136D03*
X631036Y1179921D03*
X633136D03*
X631036Y1176180D03*
X633136D03*
X638704Y562188D03*
Y565388D03*
Y568588D03*
Y571988D03*
Y575388D03*
X651837Y1136909D03*
X649737D03*
X651837Y1144389D03*
X649737D03*
X651837Y1151869D03*
X649737D03*
Y1148129D03*
X651837D03*
X640037D03*
X642137D03*
X638517Y1144389D03*
X640617D03*
X638500Y1151870D03*
X640600D03*
X638500Y1155610D03*
X640600D03*
X638500Y1166830D03*
X640600D03*
X649817D03*
X651917D03*
X638500Y1159350D03*
X640600D03*
X638500Y1162500D03*
X640600D03*
X638500Y1170570D03*
X640600D03*
X651837Y1178250D03*
X649737D03*
Y1181791D03*
X651837D03*
X651637Y1185100D03*
X649537D03*
X639850Y1174900D03*
X641950D03*
X638500Y1185342D03*
X640600D03*
X638537Y1181800D03*
X640637D03*
X638537Y1178000D03*
X640637D03*
X645177Y1193011D03*
X647277D03*
X652657D03*
X650557D03*
X657298Y1166830D03*
X659398D03*
X664778D03*
X666878D03*
X672258D03*
X674358D03*
X679739D03*
X681839D03*
X687219D03*
X689319D03*
X699179D03*
X701279D03*
X695899D03*
X693799D03*
X713400D03*
X715500D03*
X705920D03*
X708020D03*
X727460Y1133169D03*
X729560D03*
X727460Y1129429D03*
X729560D03*
X734121Y1136909D03*
X732021D03*
X734121Y1140649D03*
X732021D03*
X734121Y1144389D03*
X732021D03*
X726640Y1155610D03*
X724540D03*
X730381Y1159350D03*
X728281D03*
X730450Y1162800D03*
X728350D03*
X730381Y1166830D03*
X728281D03*
X720800D03*
X722900D03*
X730381Y1170570D03*
X728281D03*
Y1189271D03*
X730381D03*
X728281Y1185531D03*
X730381D03*
Y1181791D03*
X728281D03*
X726640Y1174310D03*
X724540D03*
X728281Y1193011D03*
X730381D03*
X745013Y440124D03*
X747113D03*
X745013Y430124D03*
X747113D03*
X745013Y433524D03*
X747113D03*
X745013Y436924D03*
X747113D03*
X745013Y443324D03*
X747113D03*
X737861Y1155610D03*
X735761D03*
X745341Y1164960D03*
X743241D03*
X745341Y1161220D03*
X743241D03*
X745341Y1168700D03*
X743241D03*
X745341Y1172440D03*
X743241D03*
X737861Y1159350D03*
X735761D03*
X737861Y1170570D03*
X735761D03*
X737861Y1166830D03*
X735761D03*
X745341Y1157480D03*
X743241D03*
X737861Y1174310D03*
X735761D03*
X734941Y1181791D03*
X737041D03*
X742421D03*
X740321D03*
X883265Y1100705D03*
X881165D03*
X910013Y1008536D03*
X912113D03*
X909959Y1011750D03*
X912059D03*
X921107Y1090015D03*
X923207D03*
X1088122Y1153740D03*
X1090222D03*
X1088122Y1149999D03*
X1090222D03*
X1088122Y1164960D03*
X1090222D03*
X1088122Y1161220D03*
X1090222D03*
X1088122Y1157480D03*
X1090222D03*
X1088122Y1181791D03*
X1090222D03*
X1088122Y1178051D03*
X1090222D03*
X1088122Y1174310D03*
X1090222D03*
X1095791Y568588D03*
X1093691D03*
X1095791Y565388D03*
X1093691D03*
X1095791Y562188D03*
X1093691D03*
X1095791Y571988D03*
X1093691D03*
X1095791Y575388D03*
X1093691D03*
X1106823Y1136909D03*
Y1151869D03*
Y1148129D03*
Y1144389D03*
X1095623Y1155610D03*
X1097723D03*
X1095623Y1151870D03*
X1097723D03*
X1095603Y1142579D03*
X1097703D03*
X1097123Y1148129D03*
X1099223D03*
X1107003Y1166830D03*
X1095623Y1170570D03*
X1097723D03*
X1095623Y1166830D03*
X1097723D03*
X1095623Y1162450D03*
X1097723D03*
X1095623Y1159350D03*
X1097723D03*
X1106623Y1185100D03*
X1106823Y1181791D03*
Y1178250D03*
X1095623Y1185200D03*
X1097723D03*
X1095623Y1181800D03*
X1097723D03*
X1095623Y1178000D03*
X1097723D03*
X1097123Y1174310D03*
X1099223D03*
X1107643Y1193011D03*
X1102263D03*
X1104363D03*
X1108923Y1136909D03*
Y1151869D03*
Y1148129D03*
Y1144389D03*
X1121964Y1166830D03*
X1124064D03*
X1114484D03*
X1116584D03*
X1109103D03*
X1108723Y1185100D03*
X1108923Y1181791D03*
Y1178250D03*
X1109743Y1193011D03*
X1136925Y1166830D03*
X1139025D03*
X1129444D03*
X1131544D03*
X1156123Y1166900D03*
X1153223D03*
X1151123D03*
X1144305Y1166830D03*
X1146405D03*
X1170486D03*
X1172586D03*
X1163006D03*
X1165106D03*
X1158223Y1166900D03*
X1189107Y1140649D03*
Y1136909D03*
X1184546Y1133169D03*
X1186646D03*
X1184546Y1129429D03*
X1186646D03*
X1189107Y1144389D03*
X1183726Y1155610D03*
X1181626D03*
X1187467Y1170570D03*
X1185367D03*
X1187467Y1166830D03*
X1185367D03*
X1187467Y1159350D03*
X1185367D03*
X1177886Y1166830D03*
X1179986D03*
X1185367Y1189271D03*
X1187467D03*
X1185367Y1185531D03*
X1187467D03*
Y1181791D03*
X1185367D03*
X1184546Y1178051D03*
X1182446D03*
X1183726Y1174310D03*
X1181626D03*
X1185367Y1193011D03*
X1187467D03*
X1202100Y433524D03*
X1204200D03*
X1202100Y430124D03*
X1204200D03*
X1202100Y440124D03*
X1204200D03*
X1202100Y436924D03*
X1204200D03*
X1202100Y443324D03*
X1204200D03*
X1191207Y1140649D03*
Y1136909D03*
X1194947Y1155610D03*
X1192847D03*
X1191207Y1144389D03*
X1202427Y1172440D03*
X1200327D03*
X1202427Y1168700D03*
X1200327D03*
X1202427Y1164960D03*
X1200327D03*
X1202427Y1161220D03*
X1200327D03*
X1202427Y1157480D03*
X1200327D03*
X1194947Y1170570D03*
X1192847D03*
X1194947Y1166830D03*
X1192847D03*
X1194947Y1159350D03*
X1192847D03*
X1194947Y1174310D03*
X1192847D03*
X1192027Y1181791D03*
X1194127D03*
X1199507D03*
X1197407D03*
X1375020Y1254104D03*
X1372920D03*
X1375020Y1247512D03*
X1372920D03*
X1375020Y1250700D03*
X1372920D03*
X1379490Y1254104D03*
X1381590D03*
X1379490Y1247512D03*
X1381590D03*
X1379490Y1250814D03*
X1381590D03*
X1379490Y1244109D03*
X1381590D03*
X1545209Y1149999D03*
Y1153740D03*
Y1157480D03*
Y1161220D03*
Y1164960D03*
Y1174310D03*
Y1178051D03*
Y1181791D03*
X1552878Y568588D03*
X1550778D03*
X1552878Y565388D03*
X1550778D03*
X1552878Y562188D03*
X1550778D03*
X1552878Y571988D03*
X1550778D03*
X1552878Y575388D03*
X1550778D03*
X1552690Y1144389D03*
X1554790D03*
X1554210Y1148129D03*
X1556310D03*
X1552710Y1155610D03*
X1554810D03*
X1552710Y1151870D03*
X1554810D03*
X1547309Y1149999D03*
Y1153740D03*
X1552710Y1170570D03*
X1554810D03*
X1552710Y1166830D03*
X1554810D03*
X1552710Y1162450D03*
X1554810D03*
X1552710Y1159350D03*
X1554810D03*
X1547309Y1157480D03*
Y1161220D03*
Y1164960D03*
X1552710Y1185200D03*
X1554810D03*
X1552710Y1181800D03*
X1554810D03*
X1552710Y1178000D03*
X1554810D03*
X1554210Y1174310D03*
X1556310D03*
X1547309D03*
Y1178051D03*
Y1181791D03*
X1559350Y1193011D03*
X1561450D03*
X1566010Y1136909D03*
X1563910D03*
X1566010Y1144389D03*
X1563910D03*
Y1148129D03*
X1566010D03*
Y1151869D03*
X1563910D03*
X1564090Y1166830D03*
X1566190D03*
X1571571D03*
X1573671D03*
X1579051D03*
X1566010Y1178250D03*
X1563910D03*
Y1181791D03*
X1566010D03*
X1565810Y1185100D03*
X1563710D03*
X1566830Y1193011D03*
X1564730D03*
X1586531Y1166830D03*
X1588631D03*
X1594012D03*
X1581151D03*
X1601392D03*
X1603492D03*
X1610310Y1166900D03*
X1608210D03*
X1596112Y1166830D03*
X1613210Y1166900D03*
X1615310D03*
X1620093Y1166830D03*
X1622193D03*
X1627573D03*
X1641633Y1129429D03*
X1643733D03*
X1641633Y1133169D03*
X1643733D03*
X1640813Y1155610D03*
X1638713D03*
X1634973Y1166830D03*
X1637073D03*
X1642454Y1159350D03*
Y1166830D03*
Y1170570D03*
X1629673Y1166830D03*
X1640813Y1174310D03*
X1638713D03*
X1641633Y1178051D03*
X1639533D03*
X1642454Y1181791D03*
Y1185531D03*
Y1189271D03*
Y1193011D03*
X1659187Y436924D03*
Y433524D03*
Y430124D03*
Y440124D03*
Y443324D03*
X1648294Y1136909D03*
X1646194D03*
X1648294Y1140649D03*
X1646194D03*
X1648294Y1144389D03*
X1646194D03*
X1652034Y1155610D03*
X1649934D03*
X1652034Y1159350D03*
X1649934D03*
X1652034Y1166830D03*
X1649934D03*
X1652034Y1170570D03*
X1649934D03*
X1659514Y1157480D03*
X1657414D03*
X1659514Y1161220D03*
X1657414D03*
X1659514Y1164960D03*
X1657414D03*
X1659514Y1168700D03*
X1657414D03*
X1659514Y1172440D03*
X1657414D03*
X1644554Y1159350D03*
Y1166830D03*
Y1170570D03*
X1652034Y1174310D03*
X1649934D03*
X1656594Y1181791D03*
X1654494D03*
X1649114D03*
X1651214D03*
X1644554D03*
Y1185531D03*
Y1189271D03*
Y1193011D03*
X1661287Y436924D03*
Y433524D03*
Y430124D03*
Y440124D03*
Y443324D03*
X1769937Y1073611D03*
X1772037D03*
X1769857Y1076717D03*
X1771957D03*
X1769858Y1090841D03*
X1771958D03*
X1789492Y1091246D03*
X1791592D03*
G54D60*
X414519Y1251852D03*
Y1264254D03*
X512830Y1251852D03*
Y1264254D03*
X1328693Y1251852D03*
Y1264254D03*
X1427004Y1251852D03*
Y1264254D03*
G54D15*
X15023Y1070592D03*
X9223D03*
X15023Y1065299D03*
X9223D03*
X15076Y1075972D03*
X9276D03*
X14968Y1081286D03*
X9168D03*
X14970Y1086527D03*
X9170D03*
X14974Y1091945D03*
X9174D03*
X33686Y1086732D03*
X47137Y1064774D03*
X52937D03*
X39486Y1086732D03*
X166249Y1125408D03*
X172049D03*
X185369Y1189089D03*
X191169D03*
X208242Y1162291D03*
X214042D03*
X223203D03*
X229003D03*
X241904D03*
X247704D03*
X295198Y1163090D03*
X300998D03*
X311962Y1163079D03*
X306162D03*
X435198Y1314391D03*
X440998D03*
X501412Y681478D03*
X507212D03*
X501412Y687978D03*
X507212D03*
X502655Y693245D03*
X508455D03*
X521414Y717903D03*
X514383Y723583D03*
X520183D03*
X527214Y717903D03*
X532304Y797889D03*
X538104D03*
Y803389D03*
X532304D03*
X551804Y806889D03*
Y801389D03*
X557604Y806889D03*
Y801389D03*
X625146Y1126058D03*
X630946D03*
X642456Y1189089D03*
X648256D03*
X665329Y1162291D03*
X680290D03*
X686090D03*
X671129D03*
X698991D03*
X704791D03*
X752285Y1163090D03*
X758085D03*
X763249Y1163079D03*
X769049D03*
X860009Y1073297D03*
X854209D03*
X859852Y1089261D03*
X854052D03*
X859847Y1083918D03*
X854047D03*
X859989Y1078510D03*
X854189D03*
X859778Y1100734D03*
X853978D03*
X859827Y1094715D03*
X854027D03*
X868191Y827563D03*
X873991D03*
X868191Y822176D03*
X873991D03*
X868191Y833037D03*
X873991D03*
X881648Y1093445D03*
X893856Y1074510D03*
X887448Y1093445D03*
X900049Y551863D03*
X905849D03*
X912866Y832855D03*
X907066D03*
X899656Y1074510D03*
X921549Y572863D03*
X927349D03*
X927014Y1074367D03*
X921214D03*
X927095Y1085168D03*
X921295D03*
X926987Y1079821D03*
X921187D03*
X936229Y843950D03*
X942029D03*
X941933Y849373D03*
X936133D03*
X960850Y807855D03*
X955050D03*
X960850Y813342D03*
X955050D03*
X960850Y818829D03*
X955050D03*
X1009116Y316394D03*
X997020Y336954D03*
X1002820D03*
Y341954D03*
X997020D03*
X1003520Y348954D03*
X1009320D03*
Y353954D03*
X1003520D03*
X1021743Y306927D03*
X1027543D03*
X1014916Y316394D03*
X1043020Y343954D03*
X1052820Y316954D03*
X1047020D03*
X1048820Y343954D03*
X1086222Y1125408D03*
X1080422D03*
X1089700Y1521000D03*
X1105342Y1189089D03*
X1099542D03*
X1095500Y1521000D03*
X1122415Y1162291D03*
X1137376D03*
X1128215D03*
X1156077D03*
X1143176D03*
X1161877D03*
X1220335Y1163079D03*
X1215171Y1163090D03*
X1209371D03*
X1226135Y1163079D03*
X1287605Y897416D03*
X1300974Y846670D03*
X1299184Y863988D03*
X1293405Y897416D03*
X1306774Y846670D03*
X1304984Y863988D03*
X1378578Y1258399D03*
X1372778D03*
X1390449Y854121D03*
X1396249D03*
X1388924Y880908D03*
X1394724D03*
X1497063Y925240D03*
Y930740D03*
X1502863Y925240D03*
Y930740D03*
X1522363Y928740D03*
X1516563D03*
Y934240D03*
X1522363D03*
X1543309Y1125408D03*
X1537509D03*
X1562429Y1189089D03*
X1556629D03*
X1579502Y1162291D03*
X1594463D03*
X1585302D03*
X1600263D03*
X1618964D03*
X1613164D03*
X1672258Y1163090D03*
X1666458D03*
X1677422Y1163079D03*
X1683222D03*
X1773994Y1080874D03*
X1768194D03*
X1773915Y1086114D03*
X1768115D03*
X1773915Y1101159D03*
X1768115D03*
X1774017Y1095803D03*
X1768217D03*
X1788794Y1095629D03*
X1783536Y1101077D03*
X1789336D03*
X1802379Y1074480D03*
X1794594Y1095629D03*
X1808179Y1074480D03*
G54D51*
X228024Y602656D03*
Y607774D03*
Y605215D03*
X236686Y602656D03*
Y607774D03*
G54D33*
X46348Y1727941D03*
Y1737941D03*
X46248Y1760941D03*
Y1750941D03*
X46348Y1773941D03*
Y1783941D03*
X46248Y1806941D03*
Y1796941D03*
X318448Y1727941D03*
Y1737941D03*
Y1750941D03*
Y1760941D03*
Y1773941D03*
Y1783941D03*
X318348Y1796941D03*
Y1806941D03*
X333286Y1728583D03*
Y1738583D03*
X333112Y1751624D03*
X333212Y1774624D03*
X333112Y1761624D03*
X333212Y1784624D03*
Y1797624D03*
Y1807624D03*
X605386Y1728583D03*
Y1738583D03*
X605312Y1751624D03*
Y1774624D03*
Y1761624D03*
Y1784624D03*
Y1807624D03*
Y1797624D03*
X620083Y1728286D03*
Y1738286D03*
X619861Y1751765D03*
X619711Y1775438D03*
X619861Y1761765D03*
X619711Y1785438D03*
X619475Y1798845D03*
Y1808845D03*
X892183Y1728286D03*
Y1738286D03*
X891911Y1751765D03*
X891761Y1775438D03*
X891911Y1761765D03*
X891761Y1785438D03*
X891525Y1808845D03*
Y1798845D03*
X907279Y1738990D03*
Y1728990D03*
X907163Y1752566D03*
Y1762566D03*
X907073Y1776014D03*
Y1786014D03*
X907166Y1800435D03*
Y1810435D03*
X1179329Y1728990D03*
Y1738990D03*
X1179263Y1752566D03*
Y1762566D03*
X1179123Y1776014D03*
Y1786014D03*
X1179216Y1800435D03*
Y1810435D03*
G54D42*
X109882Y1622402D03*
X283110D03*
X456339D03*
X629567D03*
X1131850D03*
X1305079D03*
X1478307D03*
X1651535D03*
G54D70*
X501267Y830468D03*
Y833027D03*
Y835586D03*
X507821Y846830D03*
X499947D03*
X507821Y844271D03*
X499947D03*
X507821Y849389D03*
X499947D03*
X509141Y830468D03*
Y833027D03*
Y835586D03*
X1466026Y960378D03*
Y957819D03*
Y962937D03*
X1464706Y974181D03*
Y976740D03*
Y971622D03*
X1473900Y960378D03*
Y957819D03*
Y962937D03*
X1472580Y974181D03*
Y976740D03*
Y971622D03*
X1506626Y876339D03*
X1514500D03*
X1506626Y873780D03*
X1514500D03*
X1506626Y878898D03*
X1514500D03*
G54D52*
X227803Y616063D03*
Y623543D03*
X237449Y616063D03*
Y619803D03*
Y623543D03*
G54D16*
X15713Y1116633D03*
Y1125633D03*
X15767Y1134705D03*
Y1142705D03*
X17767Y1503569D03*
X22713Y1116633D03*
Y1125633D03*
X22767Y1134705D03*
Y1142705D03*
X24767Y1503569D03*
X49542Y1110100D03*
Y1119100D03*
X49701Y1129688D03*
Y1137688D03*
X56542Y1110100D03*
Y1119100D03*
X56701Y1129688D03*
Y1137688D03*
X398190Y1093068D03*
X405190D03*
X398184Y1085881D03*
X405184D03*
X397068Y1291261D03*
X404068D03*
X425725Y1331356D03*
X439744Y1093088D03*
X432725Y1331356D03*
X446744Y1093088D03*
X463777Y1093068D03*
X470777D03*
X505331Y1093088D03*
X505189Y1085890D03*
X512331Y1093088D03*
X512189Y1085890D03*
X862403Y1125636D03*
Y1134636D03*
X862580Y1152080D03*
Y1144080D03*
X869403Y1125636D03*
Y1134636D03*
X869580Y1152080D03*
Y1144080D03*
X896232Y1119103D03*
Y1128103D03*
X896701Y1141169D03*
Y1149169D03*
X903232Y1119103D03*
Y1128103D03*
X903701Y1141169D03*
Y1149169D03*
X926380Y1125636D03*
Y1134636D03*
X926558Y1143708D03*
Y1151708D03*
X933380Y1125636D03*
Y1134636D03*
X933558Y1143708D03*
Y1151708D03*
X960209Y1119103D03*
X960678Y1141169D03*
X960209Y1128103D03*
X960678Y1149169D03*
X967209Y1119103D03*
X967678Y1141169D03*
X967209Y1128103D03*
X967678Y1149169D03*
X1312364Y1093068D03*
X1319364D03*
X1312358Y1085881D03*
X1319358D03*
X1360918Y1093088D03*
X1353918D03*
X1377951Y1093068D03*
X1384951D03*
X1426363Y1085890D03*
X1419363D03*
X1426505Y1093088D03*
X1419505D03*
X1776360Y1126122D03*
X1783360D03*
X1776360Y1135122D03*
X1783360D03*
X1776360Y1151822D03*
X1783360D03*
X1776360Y1143822D03*
X1783360D03*
X1815189Y1119589D03*
X1808189D03*
X1815189Y1128589D03*
X1808189D03*
X1815189Y1140912D03*
X1808189D03*
X1815189Y1148912D03*
X1808189D03*
G54D25*
X28216Y1323770D03*
X96116Y21782D03*
X105562Y825539D03*
X521365Y331801D03*
X658199Y944517D03*
X787032Y1631625D03*
X828878Y560702D03*
X906500Y61964D03*
X1244161Y960023D03*
X1308242Y547162D03*
X1349086Y176019D03*
X1680546Y34636D03*
X1779102Y1562706D03*
X1795900Y852600D03*
G54D61*
X398820Y1272093D03*
Y1276293D03*
X527136Y1288800D03*
Y1293000D03*
X1312889Y1291111D03*
Y1295311D03*
X1441309Y1288800D03*
Y1293000D03*
G54D34*
X65265Y822718D03*
X68869Y876608D03*
X56903Y905500D03*
Y901500D03*
X75981Y874859D03*
X85697Y664443D03*
X193616Y594400D03*
Y602400D03*
Y598400D03*
Y606400D03*
Y610400D03*
Y614400D03*
X216241Y623398D03*
X241025Y427029D03*
Y435029D03*
Y431029D03*
X274516Y388000D03*
Y384500D03*
X268879Y442606D03*
Y446606D03*
X270186Y463479D03*
X279171Y463235D03*
X281016Y388000D03*
X286987Y455152D03*
Y451152D03*
X388793Y1392591D03*
X388498Y1485778D03*
X387891Y1482239D03*
X400155Y1297965D03*
X395020Y1307238D03*
X401524Y1313443D03*
X395494Y1497835D03*
X422224Y1366972D03*
X413400Y1541221D03*
Y1547198D03*
X435850Y333907D03*
X436180Y342874D03*
X435068Y349675D03*
X429788Y1389026D03*
Y1385026D03*
X455714Y1197471D03*
X445422Y1293045D03*
X461717Y644087D03*
X468388Y1193471D03*
X488009Y791025D03*
X504157Y697405D03*
X503402Y712755D03*
Y708755D03*
X493450Y1024165D03*
X493438Y1028165D03*
X522240Y671119D03*
X514773Y831662D03*
X513843Y901500D03*
Y905500D03*
X525999Y600790D03*
X534257Y792649D03*
X525809Y876608D03*
X532921Y874859D03*
X541220Y830889D03*
Y835389D03*
X582319Y936807D03*
X650702Y594400D03*
Y602400D03*
Y598400D03*
Y606400D03*
Y610400D03*
Y614400D03*
X697035Y766471D03*
Y753471D03*
X697021Y771159D03*
Y784659D03*
X731602Y388000D03*
Y384500D03*
X727272Y463479D03*
X738102Y388000D03*
X744073Y455152D03*
Y451152D03*
X736257Y463235D03*
X780208Y1442282D03*
X780168Y1446194D03*
X796284Y1436240D03*
X813910Y869079D03*
X809983Y915705D03*
X815448Y920026D03*
X803150Y1429135D03*
X827637Y848986D03*
X827094Y880390D03*
X818513Y893885D03*
X822864Y921393D03*
X846864Y827419D03*
X840780Y847531D03*
X840253Y863413D03*
X840300Y871459D03*
X840253Y867413D03*
X841160Y1454159D03*
X853775Y863459D03*
Y859459D03*
Y871459D03*
Y879459D03*
Y867459D03*
X853766Y875468D03*
X864346Y869142D03*
X862765Y878942D03*
X853809Y892738D03*
X853806Y887707D03*
X853775Y883459D03*
X883760Y1456859D03*
X900965Y556363D03*
X911515Y578394D03*
X911465Y582863D03*
X911515Y586616D03*
X900683Y892455D03*
X900667Y884516D03*
X927712Y360129D03*
X927340Y366617D03*
X923296Y371739D03*
X914444Y817982D03*
X914344Y822083D03*
X934075Y1394627D03*
Y1398427D03*
Y1402227D03*
Y1406027D03*
X957449Y923116D03*
X971349Y901500D03*
Y905500D03*
X989975Y768775D03*
X982895Y876608D03*
X997723Y870398D03*
X1023935Y933822D03*
X1027311Y954222D03*
X1033822Y324752D03*
X1033801Y337736D03*
X1033868Y333519D03*
X1088806Y1537257D03*
X1107789Y594400D03*
Y602400D03*
Y598400D03*
Y606400D03*
Y610400D03*
Y614400D03*
X1098316Y1513398D03*
X1128691Y768859D03*
X1155198Y427029D03*
Y431029D03*
Y435029D03*
X1146001Y800642D03*
Y806642D03*
X1188689Y384500D03*
Y388000D03*
X1184359Y463479D03*
X1195189Y388000D03*
X1201160Y455152D03*
Y451152D03*
X1193344Y463235D03*
X1198235Y953789D03*
Y982789D03*
X1276233Y905173D03*
X1296516Y879800D03*
X1287980Y885651D03*
X1296516Y887800D03*
Y883800D03*
X1296970Y911478D03*
X1303016Y944000D03*
X1338435Y336999D03*
X1338765Y345966D03*
X1337653Y352767D03*
X1365716Y1422900D03*
X1382949Y561000D03*
Y607500D03*
X1382562Y1193471D03*
X1369888Y1197471D03*
X1402155Y961181D03*
X1407522Y1024254D03*
Y1028267D03*
X1428016Y905500D03*
Y901500D03*
X1442049Y601079D03*
X1439982Y876608D03*
X1447094Y874859D03*
X1440516Y931500D03*
Y936000D03*
X1479532Y959013D03*
X1491562Y327200D03*
X1492016Y318000D03*
X1485079Y880839D03*
Y870339D03*
X1492079Y880839D03*
Y870339D03*
X1499016Y920000D03*
X1505979Y958240D03*
Y962740D03*
X1564876Y602400D03*
Y598400D03*
Y594400D03*
Y606400D03*
Y610400D03*
Y614400D03*
X1612285Y427029D03*
Y431029D03*
Y435029D03*
X1640139Y442606D03*
Y446606D03*
X1641446Y463479D03*
X1652276Y388000D03*
X1645776D03*
Y384500D03*
X1658247Y455152D03*
Y451152D03*
X1650431Y463235D03*
X1789490Y989590D03*
X1798579Y964660D03*
X1801955Y985060D03*
G54D43*
X118543Y1452717D03*
X127205Y1622402D03*
X135866Y1452717D03*
X144528Y1622402D03*
X153189Y1452717D03*
X161850Y1622402D03*
X170512Y1452717D03*
X179173Y1489331D03*
Y1494449D03*
Y1504685D03*
Y1509804D03*
Y1560985D03*
Y1566103D03*
Y1576339D03*
Y1581457D03*
Y1591693D03*
Y1596811D03*
Y1607048D03*
Y1612166D03*
Y1622402D03*
X187835Y1452717D03*
Y1493662D03*
Y1498780D03*
Y1509016D03*
Y1514134D03*
Y1565315D03*
Y1570434D03*
Y1580670D03*
Y1585788D03*
X291771Y1452717D03*
X309094D03*
X300433Y1622402D03*
X326417Y1452717D03*
X317756Y1622402D03*
X343740Y1452717D03*
X335078Y1622402D03*
X361063Y1452717D03*
X352401Y1458622D03*
Y1463741D03*
X361063Y1462953D03*
Y1468071D03*
X352401Y1473977D03*
Y1479095D03*
X361063Y1478308D03*
Y1483426D03*
X352401Y1489331D03*
Y1494449D03*
X361063Y1493662D03*
Y1498780D03*
X352401Y1504685D03*
Y1509804D03*
X361063Y1509016D03*
Y1514134D03*
X352401Y1560985D03*
Y1566103D03*
X361063Y1565315D03*
Y1570434D03*
X352401Y1576339D03*
Y1581457D03*
X361063Y1580670D03*
Y1585788D03*
X352401Y1591693D03*
Y1596811D03*
Y1607048D03*
Y1612166D03*
Y1622402D03*
X465000Y1452717D03*
X473662Y1622402D03*
X482323Y1452717D03*
X490985Y1622402D03*
X499646Y1452717D03*
X516969D03*
X508307Y1622402D03*
X534292Y1452717D03*
X525630Y1458622D03*
Y1463741D03*
X534292Y1462953D03*
Y1468071D03*
X525630Y1473977D03*
Y1479095D03*
X534292Y1478308D03*
Y1483426D03*
X525630Y1489331D03*
Y1494449D03*
X534292Y1493662D03*
Y1498780D03*
X525630Y1504685D03*
Y1509804D03*
X534292Y1509016D03*
Y1514134D03*
X525630Y1560985D03*
Y1566103D03*
X534292Y1565315D03*
Y1570434D03*
X525630Y1576339D03*
Y1581457D03*
X534292Y1580670D03*
Y1585788D03*
X525630Y1591693D03*
X534292Y1596024D03*
X525630Y1596811D03*
X534292Y1601142D03*
X525630Y1607048D03*
Y1612166D03*
X534292Y1611378D03*
Y1616496D03*
X525630Y1622402D03*
X638228Y1452717D03*
X646890Y1622402D03*
X655551Y1452717D03*
X664213Y1622402D03*
X672874Y1452717D03*
X681535Y1622402D03*
X698858Y1458622D03*
Y1463741D03*
X690197Y1452717D03*
X698858Y1473977D03*
Y1479095D03*
Y1489331D03*
Y1494449D03*
Y1504685D03*
Y1509804D03*
Y1560985D03*
Y1566103D03*
Y1576339D03*
Y1581457D03*
Y1591693D03*
Y1596811D03*
Y1607048D03*
Y1612166D03*
Y1622402D03*
X707520Y1452717D03*
Y1462953D03*
Y1468071D03*
Y1478308D03*
Y1483426D03*
Y1493662D03*
Y1498780D03*
Y1509016D03*
Y1514134D03*
Y1565315D03*
Y1570434D03*
Y1580670D03*
Y1585788D03*
Y1596024D03*
Y1601142D03*
Y1611378D03*
Y1616496D03*
X1140511Y1452717D03*
X1149173Y1622402D03*
X1157834Y1452717D03*
X1166496Y1622402D03*
X1175157Y1452717D03*
X1183818Y1622402D03*
X1201141Y1458622D03*
Y1463741D03*
X1192480Y1452717D03*
X1201141Y1473977D03*
Y1479095D03*
Y1489331D03*
Y1494449D03*
Y1504685D03*
Y1509804D03*
Y1560985D03*
Y1566103D03*
Y1576339D03*
Y1581457D03*
Y1591693D03*
Y1596811D03*
Y1607048D03*
Y1612166D03*
Y1622402D03*
X1209803Y1452717D03*
Y1462953D03*
Y1468071D03*
Y1478308D03*
Y1483426D03*
Y1493662D03*
Y1498780D03*
Y1509016D03*
Y1514134D03*
Y1565315D03*
Y1570434D03*
Y1580670D03*
Y1585788D03*
Y1596024D03*
Y1601142D03*
Y1611378D03*
Y1616496D03*
X1313740Y1452717D03*
X1331063D03*
X1322402Y1622402D03*
X1348386Y1452717D03*
X1339725Y1622402D03*
X1365709Y1452717D03*
X1357047Y1622402D03*
X1383032Y1452717D03*
X1374370Y1458622D03*
Y1463741D03*
X1383032Y1462953D03*
Y1468071D03*
X1374370Y1473977D03*
Y1479095D03*
X1383032Y1478308D03*
Y1483426D03*
X1374370Y1489331D03*
Y1494449D03*
X1383032Y1493662D03*
Y1498780D03*
X1374370Y1504685D03*
Y1509804D03*
X1383032Y1509016D03*
Y1514134D03*
X1374370Y1560985D03*
Y1566103D03*
X1383032Y1565315D03*
Y1570434D03*
X1374370Y1576339D03*
Y1581457D03*
X1383032Y1580670D03*
Y1585788D03*
X1374370Y1591693D03*
X1383032Y1596024D03*
X1374370Y1596811D03*
X1383032Y1601142D03*
X1374370Y1607048D03*
Y1612166D03*
X1383032Y1611378D03*
Y1616496D03*
X1374370Y1622402D03*
X1486968Y1452717D03*
X1495630Y1622402D03*
X1504291Y1452717D03*
X1512953Y1622402D03*
X1521614Y1452717D03*
X1530275Y1622402D03*
X1538937Y1452717D03*
X1556260D03*
X1547598Y1458622D03*
Y1463741D03*
X1556260Y1462953D03*
Y1468071D03*
X1547598Y1473977D03*
Y1479095D03*
X1556260Y1478308D03*
Y1483426D03*
X1547598Y1489331D03*
Y1494449D03*
X1556260Y1493662D03*
Y1498780D03*
X1547598Y1504685D03*
Y1509804D03*
X1556260Y1509016D03*
Y1514134D03*
X1547598Y1560985D03*
Y1566103D03*
X1556260Y1565315D03*
Y1570434D03*
X1547598Y1576339D03*
Y1581457D03*
X1556260Y1580670D03*
Y1585788D03*
X1547598Y1591693D03*
X1556260Y1596024D03*
X1547598Y1596811D03*
X1556260Y1601142D03*
X1547598Y1607048D03*
Y1612166D03*
X1556260Y1611378D03*
Y1616496D03*
X1547598Y1622402D03*
X1660196Y1452717D03*
X1668858Y1622402D03*
X1677519Y1452717D03*
X1686181Y1622402D03*
X1694842Y1452717D03*
X1703503Y1622402D03*
X1720826Y1458622D03*
Y1463741D03*
X1712165Y1452717D03*
X1720826Y1473977D03*
Y1479095D03*
Y1489331D03*
Y1494449D03*
Y1504685D03*
Y1509804D03*
Y1560985D03*
Y1566103D03*
Y1576339D03*
Y1581457D03*
Y1591693D03*
Y1596811D03*
Y1607048D03*
Y1612166D03*
Y1622402D03*
X1729488Y1452717D03*
Y1462953D03*
Y1468071D03*
Y1478308D03*
Y1483426D03*
Y1493662D03*
Y1498780D03*
Y1509016D03*
Y1514134D03*
Y1565315D03*
Y1570434D03*
Y1580670D03*
Y1585788D03*
Y1596024D03*
Y1601142D03*
Y1611378D03*
Y1616496D03*
G54D71*
X555682Y826212D03*
Y834086D03*
X558241Y826212D03*
X560800D03*
X558241Y834086D03*
X560800D03*
X583501Y797111D03*
X580942D03*
X586060D03*
X583501Y804985D03*
X580942D03*
X586060D03*
X1523000Y961437D03*
Y953563D03*
X1520441Y961437D03*
Y953563D03*
X1525559Y961437D03*
Y953563D03*
G54D17*
X26789Y1373669D03*
X184851Y334492D03*
X235433Y1580079D03*
Y1626339D03*
X581890Y1580079D03*
Y1626339D03*
X1259055Y1580079D03*
Y1626339D03*
X1605512Y1580079D03*
Y1626339D03*
X1796847Y1517889D03*
X1809883Y120792D03*
G54D53*
X230754Y633125D03*
Y635684D03*
Y638243D03*
X238234Y635684D03*
Y633125D03*
Y638243D03*
G54D62*
X395670Y1272093D03*
Y1276293D03*
X530286Y1288800D03*
Y1293000D03*
X1309739Y1291111D03*
Y1295311D03*
X1444459Y1288800D03*
Y1293000D03*
G54D26*
X35744Y1498350D03*
X23451Y1534239D03*
X49049Y842234D03*
X43871Y1498355D03*
X51446Y1498614D03*
X59104Y871118D03*
X63745Y880158D03*
X64007Y1219595D03*
X94962Y868330D03*
X99055Y868297D03*
X95352Y897516D03*
X91387D03*
X163539Y1135425D03*
X220500Y544016D03*
X243593Y599597D03*
X291444Y1176566D03*
X302457Y448721D03*
X298507D03*
X298125Y1139165D03*
Y1146645D03*
X391757Y1377966D03*
X408459Y1355067D03*
X404459D03*
X399959D03*
X402189Y1407662D03*
X406189D03*
X404052Y1550463D03*
X423904Y347500D03*
X425433Y1109414D03*
X410866Y1285879D03*
X414431Y1326874D03*
X418431D03*
X412779Y1365150D03*
X423517Y1376093D03*
X414203Y1410818D03*
X418203D03*
X415823Y1556287D03*
X428785Y1115912D03*
X431620Y1108989D03*
X437912Y1289289D03*
X436485Y1319310D03*
X454591Y1007282D03*
X447091Y1014282D03*
X443591D03*
X457577Y1109409D03*
X460913Y1115912D03*
X463966Y1108911D03*
X478907Y1024143D03*
X484115Y1023985D03*
X491069Y1109422D03*
X494372Y1115912D03*
X496372Y1108912D03*
X515381Y685902D03*
X513775Y673471D03*
X517775D03*
X509791Y717432D03*
X520685Y880158D03*
X516044Y871118D03*
X523200Y1109434D03*
X532248Y684313D03*
X533023Y715258D03*
X525241Y793665D03*
X534241Y822665D03*
X525741Y821165D03*
X526500Y1115912D03*
X528500Y1108912D03*
X556174Y787931D03*
X548665Y844834D03*
X555995Y868297D03*
X551902Y868330D03*
X548327Y897516D03*
X552292D03*
X558241Y840665D03*
X566231Y844812D03*
X566103Y956323D03*
X583501Y811064D03*
X620866Y1135425D03*
X677586Y544016D03*
X748531Y1176566D03*
X759543Y448721D03*
X755593D03*
X755212Y1139165D03*
Y1146645D03*
X783659Y1019428D03*
X774367Y1451106D03*
X799631Y1019428D03*
X795631D03*
X800067Y961544D03*
X803673Y1019428D03*
X807673D03*
X811673D03*
X815673D03*
X825490Y886988D03*
X832258Y906565D03*
X825146Y969664D03*
X819673Y1019428D03*
X823673D03*
X827673D03*
X831673D03*
X835000Y763016D03*
X839000Y756016D03*
X835000Y781016D03*
X839000Y774016D03*
X835000Y799016D03*
X839000Y792016D03*
Y810016D03*
X835000Y817016D03*
X836258Y906601D03*
X832952Y942814D03*
X836952D03*
X880054Y761350D03*
X874851D03*
Y774074D03*
X880054Y774064D03*
X875095Y789792D03*
X894167Y590744D03*
X886610Y761349D03*
X885110Y774059D03*
X884894Y789792D03*
X894116D03*
X887916Y803406D03*
X912665Y353623D03*
X898384Y590811D03*
X907151Y590765D03*
X903766Y820506D03*
X899816D03*
X911286Y908853D03*
X903286D03*
X907286D03*
X918819Y368887D03*
X925755Y834472D03*
X916628Y922642D03*
X920628D03*
X924628D03*
X928628D03*
X937428Y205239D03*
X931124Y834472D03*
X931261Y880643D03*
X938752Y882077D03*
X932628Y922642D03*
X936628D03*
X949058Y919977D03*
X973130Y871118D03*
X977771Y880158D03*
X971672Y1228573D03*
X980081Y360398D03*
X1008988Y868330D03*
X1005413Y897516D03*
X1007719Y953338D03*
X1020345Y341217D03*
X1013081Y868297D03*
X1013897Y897212D03*
X1028830Y341160D03*
X1055521Y1435441D03*
X1077952Y1135425D03*
X1134673Y544016D03*
X1164197Y794426D03*
X1169697D03*
X1177431Y871329D03*
Y878829D03*
X1181151Y923550D03*
X1177186Y930550D03*
X1181151D03*
X1189219Y943305D03*
X1182779Y968759D03*
X1189219Y989805D03*
X1192431Y871329D03*
Y878829D03*
X1191151Y923550D03*
X1195118Y930550D03*
X1193219Y943305D03*
X1201219D03*
X1197219D03*
X1191151Y930550D03*
X1202719Y967805D03*
X1193219Y989805D03*
X1205617Y1176566D03*
X1216630Y448721D03*
X1212680D03*
X1207219Y967805D03*
X1212298Y1139165D03*
Y1146645D03*
X1269733Y864488D03*
X1289032Y863876D03*
X1315000Y816516D03*
X1319500D03*
X1326489Y350592D03*
X1324000Y816516D03*
X1328500D03*
X1333000D03*
X1342000D03*
X1346500D03*
X1351000D03*
X1337500D03*
X1342500Y918016D03*
X1346500D03*
X1350500D03*
X1342959Y1115912D03*
X1339685Y1109410D03*
X1344959Y1108912D03*
X1358500Y918016D03*
X1354500D03*
X1362500D03*
X1366500D03*
X1361265Y1014282D03*
X1357765D03*
X1373500Y816516D03*
X1382500Y918016D03*
X1370500D03*
X1378500D03*
X1368765Y1007282D03*
X1375087Y1115912D03*
X1371792Y1109411D03*
X1377087Y1108912D03*
X1386295Y918016D03*
X1393081Y1024143D03*
X1398289Y1023985D03*
X1408546Y1115912D03*
X1405189Y1109409D03*
X1410546Y1108912D03*
X1430444Y599741D03*
X1430217Y871118D03*
X1434858Y880158D03*
X1440674Y1115912D03*
X1437352Y1109435D03*
X1442674Y1108912D03*
X1462500Y897516D03*
X1470168Y868297D03*
X1466075Y868330D03*
X1466465Y897516D03*
X1491107Y884708D03*
X1487107D03*
X1490000Y921016D03*
X1490500Y948516D03*
X1499000Y950016D03*
X1513424Y972185D03*
X1525000Y893016D03*
X1529000D03*
X1520933Y915282D03*
X1523000Y968016D03*
X1533244Y971592D03*
X1535039Y1135425D03*
X1591760Y544016D03*
X1600008Y1480769D03*
X1596038D03*
X1669767Y448721D03*
X1673717D03*
X1669385Y1139165D03*
Y1146645D03*
X1662704Y1176566D03*
X1817832Y1209498D03*
G54D35*
X68232Y822718D03*
X59870Y905500D03*
Y901500D03*
X71836Y876608D03*
X78948Y874859D03*
X88664Y664443D03*
X196583Y594400D03*
Y602400D03*
Y598400D03*
Y606400D03*
Y610400D03*
Y614400D03*
X219208Y623398D03*
X243992Y427029D03*
Y435029D03*
Y431029D03*
X277483Y388000D03*
Y384500D03*
X271846Y442606D03*
Y446606D03*
X273153Y463479D03*
X283983Y388000D03*
X289954Y455152D03*
Y451152D03*
X282138Y463235D03*
X391760Y1392591D03*
X391465Y1485778D03*
X390858Y1482239D03*
X403122Y1297965D03*
X397987Y1307238D03*
X404491Y1313443D03*
X398461Y1497835D03*
X425191Y1366972D03*
X416367Y1541221D03*
Y1547198D03*
X438817Y333907D03*
X439147Y342874D03*
X438035Y349675D03*
X432755Y1389026D03*
Y1385026D03*
X458681Y1197471D03*
X448389Y1293045D03*
X464684Y644087D03*
X471355Y1193471D03*
X490976Y791025D03*
X507124Y697405D03*
X506369Y712755D03*
Y708755D03*
X496417Y1024165D03*
X496405Y1028165D03*
X517740Y831662D03*
X516810Y901500D03*
Y905500D03*
X528966Y600790D03*
X525207Y671119D03*
X537224Y792649D03*
X528776Y876608D03*
X535888Y874859D03*
X544187Y830889D03*
Y835389D03*
X585286Y936807D03*
X653669Y594400D03*
Y602400D03*
Y598400D03*
Y606400D03*
Y610400D03*
Y614400D03*
X700002Y766471D03*
Y753471D03*
X699988Y771159D03*
Y784659D03*
X734569Y388000D03*
Y384500D03*
X730239Y463479D03*
X741069Y388000D03*
X747040Y455152D03*
Y451152D03*
X739224Y463235D03*
X783175Y1442282D03*
X783135Y1446194D03*
X799251Y1436240D03*
X812950Y915705D03*
X806117Y1429135D03*
X830604Y848986D03*
X830061Y880390D03*
X816877Y869079D03*
X821480Y893885D03*
X825831Y921393D03*
X818415Y920026D03*
X843747Y847531D03*
X843220Y863413D03*
X843267Y871459D03*
X843220Y867413D03*
X844127Y1454159D03*
X849831Y827419D03*
X856742Y863459D03*
Y859459D03*
Y871459D03*
Y879459D03*
Y867459D03*
X856733Y875468D03*
X856776Y892738D03*
X856773Y887707D03*
X856742Y883459D03*
X867313Y869142D03*
X865732Y878942D03*
X886727Y1456859D03*
X903932Y556363D03*
X903650Y892455D03*
X903634Y884516D03*
X926263Y371739D03*
X914482Y578394D03*
X914432Y582863D03*
X914482Y586616D03*
X917411Y817982D03*
X917311Y822083D03*
X930679Y360129D03*
X930307Y366617D03*
X937042Y1394627D03*
Y1398427D03*
Y1402227D03*
Y1406027D03*
X960416Y923116D03*
X974316Y901500D03*
Y905500D03*
X992942Y768775D03*
X985862Y876608D03*
X1000690Y870398D03*
X1026902Y933822D03*
X1036789Y324752D03*
X1036768Y337736D03*
X1036835Y333519D03*
X1030278Y954222D03*
X1091773Y1537257D03*
X1101283Y1513398D03*
X1110756Y594400D03*
Y602400D03*
Y598400D03*
Y606400D03*
Y610400D03*
Y614400D03*
X1131658Y768859D03*
X1148968Y800642D03*
Y806642D03*
X1158165Y427029D03*
Y431029D03*
Y435029D03*
X1187326Y463479D03*
X1198156Y388000D03*
X1191656Y384500D03*
Y388000D03*
X1204127Y455152D03*
Y451152D03*
X1196311Y463235D03*
X1201202Y953789D03*
Y982789D03*
X1279200Y905173D03*
X1299483Y879800D03*
X1290947Y885651D03*
X1299483Y887800D03*
Y883800D03*
X1299937Y911478D03*
X1305983Y944000D03*
X1341402Y336999D03*
X1341732Y345966D03*
X1340620Y352767D03*
X1372855Y1197471D03*
X1368683Y1422900D03*
X1385916Y561000D03*
Y607500D03*
X1385529Y1193471D03*
X1405122Y961181D03*
X1410489Y1024254D03*
Y1028267D03*
X1430983Y905500D03*
Y901500D03*
X1445016Y601079D03*
X1442949Y876608D03*
X1443483Y931500D03*
Y936000D03*
X1450061Y874859D03*
X1494529Y327200D03*
X1494983Y318000D03*
X1488046Y880839D03*
Y870339D03*
X1495046Y880839D03*
Y870339D03*
X1482499Y959013D03*
X1501983Y920000D03*
X1508946Y958240D03*
Y962740D03*
X1567843Y602400D03*
Y598400D03*
Y594400D03*
Y606400D03*
Y610400D03*
Y614400D03*
X1615252Y427029D03*
Y431029D03*
Y435029D03*
X1643106Y442606D03*
Y446606D03*
X1644413Y463479D03*
X1655243Y388000D03*
X1648743D03*
Y384500D03*
X1653398Y463235D03*
X1661214Y455152D03*
Y451152D03*
X1801546Y964660D03*
X1792457Y989590D03*
X1804922Y985060D03*
G54D44*
X173829Y455492D03*
Y583957D03*
X202844Y455492D03*
Y583957D03*
X266841Y421555D03*
Y550020D03*
X295856Y421555D03*
Y550020D03*
X630915Y455492D03*
Y583957D03*
X659930Y455492D03*
Y583957D03*
X723927Y421555D03*
Y550020D03*
X752942Y421555D03*
Y550020D03*
X1088002Y455492D03*
Y583957D03*
X1117017Y455492D03*
Y583957D03*
X1181014Y421555D03*
Y550020D03*
X1210029Y421555D03*
Y550020D03*
X1545089Y455492D03*
Y583957D03*
X1574104Y455492D03*
Y583957D03*
X1638101Y421555D03*
Y550020D03*
X1667116Y421555D03*
Y550020D03*
G54D80*
X895384Y228740D03*
Y276772D03*
X923336Y226772D03*
Y278740D03*
G54D18*
X11184Y1503268D03*
Y1510748D03*
X51043Y1543839D03*
Y1536359D03*
X424559Y1404286D03*
Y1411766D03*
X880949Y599123D03*
Y606603D03*
X921449Y603123D03*
Y610603D03*
X988920Y326714D03*
Y334194D03*
G54D54*
X232944Y1123810D03*
Y1129610D03*
X232916Y1205884D03*
Y1200084D03*
X404934Y324379D03*
Y318579D03*
X417325Y1217782D03*
Y1211982D03*
X424563Y1217782D03*
Y1211982D03*
X411816Y1217782D03*
Y1211982D03*
X425874Y1277211D03*
Y1283011D03*
X417305Y1362459D03*
Y1368259D03*
X439934Y1198371D03*
Y1192571D03*
X430101Y1217782D03*
Y1211982D03*
X438005Y1217782D03*
Y1211982D03*
X441044Y1277232D03*
Y1283032D03*
X436291Y1277232D03*
Y1283032D03*
X431114Y1277510D03*
Y1283310D03*
X450470Y1211982D03*
Y1217782D03*
X455811Y1211982D03*
Y1217782D03*
X443840D03*
Y1211982D03*
X456438Y1277339D03*
Y1283139D03*
X451343Y1277319D03*
Y1283119D03*
X446212Y1277264D03*
Y1283064D03*
X471348Y1211982D03*
Y1217782D03*
X466241Y1211982D03*
Y1217782D03*
X461014Y1211982D03*
Y1217782D03*
X461643Y1277361D03*
Y1283161D03*
X466973Y1277361D03*
Y1283161D03*
X472590Y1277361D03*
Y1283161D03*
X476577Y1211982D03*
Y1217782D03*
X482888Y1211982D03*
Y1217782D03*
X489047D03*
Y1211982D03*
X489119Y1277361D03*
Y1283161D03*
X478099Y1277361D03*
Y1283161D03*
X483501Y1277361D03*
Y1283161D03*
X496768Y1217782D03*
Y1211982D03*
X502202Y1217782D03*
Y1211982D03*
X494899Y1279035D03*
Y1284835D03*
X506026Y1279035D03*
Y1284835D03*
X500300Y1279035D03*
Y1284835D03*
X523741Y816549D03*
Y810749D03*
X513136Y1198371D03*
Y1192571D03*
X515463Y1217782D03*
Y1211982D03*
X510190Y1217782D03*
Y1211982D03*
X523694Y1217782D03*
Y1211982D03*
X522765Y1277845D03*
Y1283645D03*
X517332Y1277845D03*
Y1283645D03*
X511876Y1277845D03*
Y1283645D03*
X528136Y1277845D03*
Y1283645D03*
X547039Y681536D03*
X542084Y681459D03*
X547039Y687336D03*
X542084Y687259D03*
X690031Y1123810D03*
Y1129610D03*
X690003Y1205884D03*
Y1200084D03*
X877949Y566263D03*
Y560463D03*
X894949Y553963D03*
X889949D03*
X882949Y560463D03*
Y566263D03*
X894949Y559763D03*
X889949D03*
X887949Y599963D03*
Y605763D03*
X915949Y566463D03*
Y572263D03*
X914949Y603963D03*
Y609763D03*
X925114Y1095109D03*
Y1100909D03*
X930167Y1095126D03*
Y1100926D03*
X939435Y825288D03*
Y819488D03*
X942796Y872268D03*
Y878068D03*
X945889Y1095016D03*
Y1100816D03*
X940701Y1095023D03*
Y1100823D03*
X935430Y1095120D03*
Y1100920D03*
X994920Y326054D03*
Y331854D03*
X1147117Y1123810D03*
Y1129610D03*
X1147089Y1200084D03*
Y1205884D03*
X1307519Y327471D03*
Y321671D03*
X1307691Y828067D03*
Y822267D03*
X1317009Y1217914D03*
Y1212114D03*
X1311699Y1251496D03*
Y1245696D03*
X1320072Y1280152D03*
Y1285952D03*
X1314618Y1280207D03*
Y1286007D03*
X1329350Y1217914D03*
Y1212114D03*
X1323915Y1217914D03*
Y1212114D03*
X1335873Y1284287D03*
X1325444D03*
X1330594D03*
X1335873Y1290087D03*
X1325444D03*
X1330594D03*
X1352163Y1212114D03*
Y1217914D03*
X1344332D03*
Y1212114D03*
X1341137Y1284287D03*
X1346371D03*
X1351668D03*
X1341137Y1290087D03*
X1346371D03*
X1351668D03*
X1364623Y1212114D03*
Y1217914D03*
X1357630D03*
Y1212114D03*
X1356871Y1284287D03*
X1367681D03*
X1362269D03*
X1356871Y1290087D03*
X1367681D03*
X1362269D03*
X1380372Y1212114D03*
Y1217914D03*
X1375161Y1212114D03*
Y1217914D03*
X1369945Y1212114D03*
Y1217914D03*
X1373032Y1284243D03*
X1380311Y1276377D03*
Y1282177D03*
X1373032Y1290043D03*
X1396780Y896111D03*
Y901911D03*
X1397096Y1212114D03*
Y1217914D03*
X1390655Y1212114D03*
Y1217914D03*
X1385539Y1212114D03*
Y1217914D03*
X1385497Y1276433D03*
Y1282233D03*
X1400803Y1277849D03*
Y1283649D03*
X1390647Y1276399D03*
Y1282199D03*
X1395671Y1276397D03*
Y1282197D03*
X1411434Y1217914D03*
Y1212114D03*
X1416583Y1217914D03*
Y1212114D03*
X1403080Y1217914D03*
Y1212114D03*
X1412392Y1277962D03*
Y1283762D03*
X1407232Y1277952D03*
Y1283752D03*
X1427310Y1198371D03*
Y1192571D03*
X1424856Y1217914D03*
Y1212114D03*
X1430129Y1217914D03*
Y1212114D03*
X1418280Y1273336D03*
Y1279136D03*
X1430336Y1273336D03*
Y1279136D03*
X1424852Y1273336D03*
Y1279136D03*
X1438360Y1217914D03*
Y1212114D03*
X1436251Y1273336D03*
Y1279136D03*
X1442192Y1273336D03*
Y1279136D03*
X1488500Y943900D03*
Y938100D03*
X1604204Y1123810D03*
Y1129610D03*
X1604176Y1200084D03*
Y1205884D03*
G54D81*
X891012Y692138D03*
G54D63*
X409211Y1300396D03*
Y1298427D03*
Y1302364D03*
Y1312207D03*
Y1306301D03*
Y1310238D03*
Y1308270D03*
Y1304333D03*
X398881Y1383912D03*
Y1381943D03*
Y1379975D03*
Y1378006D03*
Y1391786D03*
Y1389817D03*
Y1387849D03*
Y1385880D03*
X417581Y1383912D03*
Y1381943D03*
Y1379975D03*
Y1378006D03*
Y1391786D03*
Y1389817D03*
Y1387849D03*
Y1385880D03*
X427911Y1302364D03*
Y1300396D03*
Y1298427D03*
Y1312207D03*
Y1304333D03*
Y1310238D03*
Y1306301D03*
Y1308270D03*
G54D27*
X35744Y1501317D03*
X23451Y1537206D03*
X49049Y845201D03*
X51446Y1501581D03*
X43871Y1501322D03*
X59104Y874085D03*
X63745Y883125D03*
X64007Y1222562D03*
X94962Y871297D03*
X99055Y871264D03*
X95352Y900483D03*
X91387D03*
X163539Y1138392D03*
X220500Y546983D03*
X243593Y602564D03*
X291444Y1179533D03*
X302457Y451688D03*
X298507D03*
X298125Y1142132D03*
Y1149612D03*
X391757Y1380933D03*
X408459Y1358034D03*
X404459D03*
X399959D03*
X402189Y1410629D03*
X406189D03*
X404052Y1553430D03*
X423904Y350467D03*
X425433Y1112381D03*
X410866Y1288846D03*
X414431Y1329841D03*
X418431D03*
X412779Y1368117D03*
X423517Y1379060D03*
X414203Y1413785D03*
X418203D03*
X415823Y1559254D03*
X428785Y1118879D03*
X431620Y1111956D03*
X437912Y1292256D03*
X436485Y1322277D03*
X454591Y1010249D03*
X447091Y1017249D03*
X443591D03*
X457577Y1112376D03*
X460913Y1118879D03*
X463966Y1111878D03*
X478907Y1027110D03*
X484115Y1026952D03*
X491069Y1112389D03*
X494372Y1118879D03*
X496372Y1111879D03*
X513775Y676438D03*
X517775D03*
X515381Y688869D03*
X509791Y720399D03*
X516044Y874085D03*
X520685Y883125D03*
X523200Y1112401D03*
X532248Y687280D03*
X533023Y718225D03*
X525241Y796632D03*
X534241Y825632D03*
X525741Y824132D03*
X526500Y1118879D03*
X528500Y1111879D03*
X556174Y790898D03*
X548665Y847801D03*
X555995Y871264D03*
X551902Y871297D03*
X548327Y900483D03*
X552292D03*
X558241Y843632D03*
X566231Y847779D03*
X566103Y959290D03*
X583501Y814031D03*
X620866Y1138392D03*
X677586Y546983D03*
X748531Y1179533D03*
X759543Y451688D03*
X755593D03*
X755212Y1142132D03*
Y1149612D03*
X783659Y1022395D03*
X774367Y1454073D03*
X799631Y1022395D03*
X795631D03*
X800067Y964511D03*
X803673Y1022395D03*
X807673D03*
X811673D03*
X815673D03*
X825490Y889955D03*
X832258Y909532D03*
X825146Y972631D03*
X819673Y1022395D03*
X823673D03*
X827673D03*
X831673D03*
X835000Y765983D03*
X839000Y758983D03*
Y776983D03*
X835000Y783983D03*
X839000Y794983D03*
X835000Y801983D03*
X839000Y812983D03*
X835000Y819983D03*
X836258Y909568D03*
X832952Y945781D03*
X836952D03*
X880054Y764317D03*
X874851D03*
Y777041D03*
X880054Y777031D03*
X875095Y792759D03*
X894167Y593711D03*
X886610Y764316D03*
X885110Y777026D03*
X884894Y792759D03*
X894116D03*
X887916Y806373D03*
X912665Y356590D03*
X898384Y593778D03*
X907151Y593732D03*
X903766Y823473D03*
X899816D03*
X911286Y911820D03*
X903286D03*
X907286D03*
X918819Y371854D03*
X925755Y837439D03*
X916628Y925609D03*
X920628D03*
X924628D03*
X928628D03*
X937428Y208206D03*
X931124Y837439D03*
X938752Y885044D03*
X931261Y883610D03*
X932628Y925609D03*
X936628D03*
X949058Y922944D03*
X973130Y874085D03*
X977771Y883125D03*
X971672Y1231540D03*
X980081Y363365D03*
X1008988Y871297D03*
X1005413Y900483D03*
X1007719Y956305D03*
X1020345Y344184D03*
X1013081Y871264D03*
X1013897Y900179D03*
X1028830Y344127D03*
X1055521Y1438408D03*
X1077952Y1138392D03*
X1134673Y546983D03*
X1164197Y797393D03*
X1169697D03*
X1177431Y874296D03*
Y881796D03*
X1181151Y926517D03*
X1177186Y933517D03*
X1181151D03*
X1189219Y946272D03*
X1182779Y971726D03*
X1189219Y992772D03*
X1192431Y874296D03*
Y881796D03*
X1191151Y926517D03*
X1195118Y933517D03*
X1191151D03*
X1193219Y946272D03*
X1201219D03*
X1197219D03*
X1202719Y970772D03*
X1193219Y992772D03*
X1205617Y1179533D03*
X1216630Y451688D03*
X1212680D03*
X1207219Y970772D03*
X1212298Y1142132D03*
Y1149612D03*
X1269733Y867455D03*
X1289032Y866843D03*
X1315000Y819483D03*
X1319500D03*
X1326489Y353559D03*
X1324000Y819483D03*
X1328500D03*
X1333000D03*
X1342000D03*
X1346500D03*
X1351000D03*
X1337500D03*
X1342500Y920983D03*
X1346500D03*
X1350500D03*
X1342959Y1118879D03*
X1339685Y1112377D03*
X1344959Y1111879D03*
X1358500Y920983D03*
X1354500D03*
X1362500D03*
X1366500D03*
X1361265Y1017249D03*
X1357765D03*
X1373500Y819483D03*
X1382500Y920983D03*
X1370500D03*
X1378500D03*
X1368765Y1010249D03*
X1375087Y1118879D03*
X1371792Y1112378D03*
X1377087Y1111879D03*
X1386295Y920983D03*
X1393081Y1027110D03*
X1398289Y1026952D03*
X1408546Y1118879D03*
X1405189Y1112376D03*
X1410546Y1111879D03*
X1430444Y602708D03*
X1430217Y874085D03*
X1434858Y883125D03*
X1440674Y1118879D03*
X1437352Y1112402D03*
X1442674Y1111879D03*
X1462500Y900483D03*
X1470168Y871264D03*
X1466075Y871297D03*
X1466465Y900483D03*
X1491107Y887675D03*
X1487107D03*
X1490000Y923983D03*
X1490500Y951483D03*
X1499000Y952983D03*
X1513424Y975152D03*
X1525000Y895983D03*
X1529000D03*
X1520933Y918249D03*
X1523000Y970983D03*
X1533244Y974559D03*
X1535039Y1138392D03*
X1591760Y546983D03*
X1600008Y1483736D03*
X1596038D03*
X1669767Y451688D03*
X1673717D03*
X1669385Y1142132D03*
Y1149612D03*
X1662704Y1179533D03*
X1817832Y1212465D03*
G54D90*
X1028012Y1622787D03*
G54D36*
X56348Y1727941D03*
Y1737941D03*
X56248Y1750941D03*
X56348Y1773941D03*
X56248Y1760941D03*
X56348Y1783941D03*
X56248Y1806941D03*
Y1796941D03*
X308448Y1737941D03*
Y1727941D03*
Y1750941D03*
Y1760941D03*
Y1773941D03*
Y1783941D03*
X308348Y1796941D03*
Y1806941D03*
X343286Y1738583D03*
Y1728583D03*
X343112Y1751624D03*
X343212Y1774624D03*
X343112Y1761624D03*
X343212Y1784624D03*
Y1797624D03*
Y1807624D03*
X595386Y1728583D03*
Y1738583D03*
X595312Y1751624D03*
Y1774624D03*
Y1761624D03*
Y1784624D03*
Y1807624D03*
Y1797624D03*
X630083Y1738286D03*
Y1728286D03*
X629861Y1751765D03*
X629711Y1775438D03*
X629861Y1761765D03*
X629711Y1785438D03*
X629475Y1798845D03*
Y1808845D03*
X882183Y1728286D03*
Y1738286D03*
X881911Y1751765D03*
X881761Y1775438D03*
X881911Y1761765D03*
X881761Y1785438D03*
X881525Y1798845D03*
Y1808845D03*
X917279Y1738990D03*
Y1728990D03*
X917163Y1752566D03*
Y1762566D03*
X917073Y1786014D03*
Y1776014D03*
X917166Y1800435D03*
Y1810435D03*
X1169329Y1728990D03*
Y1738990D03*
X1169263Y1752566D03*
Y1762566D03*
X1169123Y1776014D03*
Y1786014D03*
X1169216Y1800435D03*
Y1810435D03*
G54D72*
X710406Y-26826D03*
Y-36826D03*
D03*
Y-26826D03*
X735406D03*
Y-36826D03*
D03*
Y-26826D03*
X830406Y-76006D03*
D03*
Y-66006D03*
D03*
X855406Y-76006D03*
D03*
Y-66006D03*
D03*
X939542Y-36798D03*
Y-26798D03*
D03*
Y-36798D03*
X964386Y-75978D03*
D03*
Y-65978D03*
D03*
X964542Y-36798D03*
Y-26798D03*
D03*
Y-36798D03*
X989386Y-75978D03*
D03*
Y-65978D03*
D03*
X993906Y-46826D03*
Y-36826D03*
D03*
Y-26826D03*
X1018906Y-46826D03*
Y-36826D03*
D03*
Y-26826D03*
X1063906Y-76006D03*
Y-86006D03*
Y-76006D03*
Y-66006D03*
X1088906Y-76006D03*
Y-86006D03*
Y-76006D03*
Y-66006D03*
X1217686Y-85978D03*
Y-75978D03*
D03*
Y-65978D03*
X1223042Y-46928D03*
Y-36928D03*
Y-26928D03*
Y-36928D03*
X1242686Y-85978D03*
Y-75978D03*
D03*
Y-65978D03*
X1248042Y-46928D03*
Y-36928D03*
Y-26928D03*
Y-36928D03*
X1280406Y-46956D03*
Y-36956D03*
D03*
Y-26956D03*
X1305406Y-46956D03*
Y-36956D03*
D03*
Y-26956D03*
X1320406Y-76006D03*
Y-86006D03*
Y-76006D03*
Y-66006D03*
X1345406Y-76006D03*
Y-86006D03*
Y-76006D03*
Y-66006D03*
X1474186Y-85978D03*
Y-75978D03*
D03*
Y-65978D03*
X1499186Y-85978D03*
Y-75978D03*
D03*
Y-65978D03*
X1509542Y-47058D03*
Y-37058D03*
Y-27058D03*
Y-37058D03*
X1534542Y-47058D03*
Y-37058D03*
Y-27058D03*
Y-37058D03*
X1564906Y-47086D03*
Y-37086D03*
D03*
Y-27086D03*
X1574906Y-76006D03*
Y-86006D03*
Y-76006D03*
Y-66006D03*
X1589906Y-47086D03*
Y-37086D03*
D03*
Y-27086D03*
X1599906Y-76006D03*
Y-86006D03*
Y-76006D03*
Y-66006D03*
X1728686Y-85978D03*
Y-75978D03*
D03*
Y-65978D03*
X1753686Y-85978D03*
Y-75978D03*
D03*
Y-65978D03*
X1794042Y-47188D03*
Y-37188D03*
Y-27188D03*
Y-37188D03*
X1819042Y-47188D03*
Y-37188D03*
Y-27188D03*
Y-37188D03*
G54D45*
X190325Y368760D03*
X279360Y636752D03*
X647411Y368760D03*
X736446Y636752D03*
X1104498Y368760D03*
X1193533Y636752D03*
X1561585Y368760D03*
X1650620Y636752D03*
G54D28*
X28774Y1529931D03*
Y1522774D03*
X63624Y847627D03*
X59871Y897500D03*
X61977Y1511735D03*
X63463Y1525714D03*
X63487Y1518596D03*
X63437Y1531804D03*
X90097Y681800D03*
X98773Y875194D03*
Y879194D03*
X118577Y892845D03*
Y884845D03*
Y888845D03*
X159189Y1148530D03*
X159648Y1164560D03*
X159433Y1160650D03*
X159648Y1169100D03*
X183084Y550400D03*
Y554400D03*
X193870Y544967D03*
X196584Y618400D03*
X200870Y544967D03*
X261628Y438323D03*
X251025Y427017D03*
X250993Y435029D03*
Y431029D03*
X283984Y384500D03*
X282156Y467367D03*
X306767Y377912D03*
Y389912D03*
Y381912D03*
Y385912D03*
Y393924D03*
Y397912D03*
Y401924D03*
Y405924D03*
Y409924D03*
X392639Y1311289D03*
Y1315289D03*
X388462Y1384722D03*
Y1388722D03*
X395795Y1299275D03*
Y1303275D03*
X400001Y1540700D03*
Y1535200D03*
Y1547200D03*
X420633Y343005D03*
X421054Y334523D03*
X421564Y1111226D03*
X425491Y1288843D03*
X425192Y1370972D03*
X431177Y349696D03*
X438307Y1309865D03*
X428437Y1320684D03*
X433066Y1398800D03*
X433042Y1394934D03*
X453585Y1111226D03*
X458682Y1193471D03*
X448390Y1301545D03*
Y1297045D03*
Y1305545D03*
X462369Y1007325D03*
X459269Y1002180D03*
X467575Y1014566D03*
X471356Y1197471D03*
X490977Y795025D03*
X487036Y1111177D03*
X506370Y704755D03*
X500091Y790275D03*
X509225Y796149D03*
X515420Y799973D03*
Y811973D03*
Y803973D03*
Y807973D03*
X516811Y897500D03*
X519294Y1111272D03*
X536263Y708711D03*
X526013Y713581D03*
X532188Y831027D03*
X525188D03*
X532225Y836149D03*
Y840649D03*
X525225D03*
Y836149D03*
X531868Y849830D03*
X524868D03*
X555188Y796389D03*
X555713Y879194D03*
Y875194D03*
X575517Y888845D03*
Y884845D03*
Y892845D03*
X580884Y961804D03*
X616276Y1148530D03*
X616520Y1160650D03*
X616735Y1169100D03*
Y1164560D03*
X640170Y550400D03*
Y554400D03*
X650956Y544967D03*
X653670Y618400D03*
X657956Y544967D03*
X700003Y762971D03*
Y756971D03*
X699989Y780659D03*
Y775159D03*
X718714Y438323D03*
X728933Y442606D03*
Y446606D03*
X741070Y384500D03*
X739242Y467367D03*
X763853Y377912D03*
Y389912D03*
Y381912D03*
Y385912D03*
Y393924D03*
Y397912D03*
Y401924D03*
Y405924D03*
Y409924D03*
X806103Y1425152D03*
X806328Y1436240D03*
X802328Y1460979D03*
X831208Y859484D03*
X816878Y872812D03*
Y876605D03*
X845793Y835459D03*
Y839459D03*
X843748Y843490D03*
X843345Y855397D03*
X845793Y851459D03*
X845707Y875476D03*
X842942Y879459D03*
Y883459D03*
X842848Y891503D03*
X842849Y887490D03*
X834371Y1463690D03*
X864875Y388245D03*
X856743Y847459D03*
Y835459D03*
Y839459D03*
Y843459D03*
Y855459D03*
X856790Y851924D03*
X889535Y571532D03*
X890686Y577288D03*
X890743Y585773D03*
X886715Y1460847D03*
X903630Y888478D03*
X919957Y312228D03*
X915134Y360583D03*
X915365Y365893D03*
X926602Y1379411D03*
X926629Y1383264D03*
X926655Y1387039D03*
X926683Y1390841D03*
X936955Y1371951D03*
X937029Y1375878D03*
X941997Y1443901D03*
X974317Y897500D03*
X968042Y1444474D03*
X993684Y1369200D03*
Y1373400D03*
Y1385200D03*
Y1394200D03*
Y1389200D03*
X993655Y1398271D03*
X990227Y1444240D03*
X1010742Y327510D03*
Y323386D03*
Y333088D03*
Y339880D03*
X1005485Y801475D03*
X1009489Y816957D03*
X1012799Y875194D03*
Y879194D03*
X1014338Y1444512D03*
X1032603Y892845D03*
Y884845D03*
Y888845D03*
X1040004Y1444596D03*
X1046904Y337454D03*
X1073362Y1148530D03*
X1073821Y1164560D03*
Y1169100D03*
X1073606Y1160650D03*
X1091774Y1533457D03*
X1097257Y550400D03*
Y554400D03*
X1108043Y544967D03*
X1115043D03*
X1110757Y618400D03*
X1155501Y788431D03*
X1148969Y797142D03*
Y810142D03*
X1165198Y427017D03*
X1165166Y431029D03*
Y435029D03*
X1175801Y438323D03*
X1186020Y442606D03*
Y446606D03*
X1179636Y888899D03*
X1198157Y384500D03*
X1196329Y467367D03*
X1220940Y377912D03*
Y389912D03*
Y381912D03*
Y385912D03*
Y393924D03*
Y397912D03*
Y401924D03*
Y405924D03*
Y409924D03*
X1263714Y327257D03*
X1270621D03*
X1279484Y330500D03*
Y334500D03*
X1299484Y871800D03*
Y875800D03*
Y891800D03*
X1290948Y881802D03*
X1323639Y337615D03*
X1323254Y346026D03*
X1333762Y352788D03*
X1335514Y1111198D03*
X1367725D03*
X1376543Y1007325D03*
X1373443Y1002180D03*
X1381749Y1014566D03*
X1372856Y1193471D03*
X1385917Y569000D03*
Y565000D03*
Y615500D03*
Y611500D03*
X1397501Y984037D03*
X1385530Y1197471D03*
X1411799Y992861D03*
X1401172Y1111258D03*
X1410884Y1423700D03*
X1430984Y897500D03*
X1433415Y1111197D03*
X1443484Y927000D03*
X1469886Y879194D03*
Y875194D03*
X1473984Y923500D03*
X1480179Y927324D03*
Y931324D03*
Y939324D03*
Y935324D03*
X1490320Y891615D03*
X1496947Y958378D03*
X1489947D03*
X1496984Y963500D03*
X1489984D03*
X1496984Y968000D03*
X1489984D03*
X1489627Y977181D03*
X1496627D03*
X1500547Y876339D03*
X1519947Y923740D03*
X1525984Y943000D03*
X1518984D03*
X1530449Y1148530D03*
X1530693Y1160650D03*
X1530908Y1169100D03*
Y1164560D03*
X1554344Y550400D03*
Y554400D03*
X1551207Y1418847D03*
X1560206Y1418806D03*
X1565130Y544967D03*
X1572130D03*
X1567844Y618400D03*
X1588494Y341787D03*
Y337787D03*
X1622285Y427017D03*
X1622253Y431029D03*
Y435029D03*
X1632888Y438323D03*
X1655244Y384500D03*
X1653416Y467367D03*
X1678027Y377912D03*
Y389912D03*
Y381912D03*
Y385912D03*
Y393924D03*
Y397912D03*
Y401924D03*
Y405924D03*
Y409924D03*
G54D19*
X18037Y1512511D03*
X21537D03*
X63981Y1212146D03*
X96443Y890391D03*
X156299Y1135426D03*
X160039D03*
X220500Y536517D03*
X221263Y632670D03*
X223952Y1213969D03*
X246695Y633206D03*
X291444Y1184048D03*
X408523Y1327161D03*
X404657Y1327185D03*
X395959Y1355068D03*
X400879Y1400335D03*
X395111Y1490998D03*
X409981Y1534003D03*
X404157D03*
X424016Y328157D03*
X425773Y1265489D03*
X418735Y1282581D03*
X414735D03*
X416357Y1398966D03*
X410152Y1405470D03*
X430959Y328106D03*
X431822Y1122849D03*
X427997Y1122834D03*
X441078Y1263727D03*
X436325D03*
X431661Y1265489D03*
X432485Y1319311D03*
X450591Y1007283D03*
Y1014283D03*
X456377Y1023716D03*
X456472Y1263834D03*
X451377Y1263814D03*
X446246Y1263759D03*
X460377Y1023716D03*
X464385Y1023697D03*
X461677Y1263856D03*
X466975D03*
X472592Y1263824D03*
X489121D03*
X478101D03*
X483503D03*
X505791Y717433D03*
X497357Y1122954D03*
X493532Y1122929D03*
X494901Y1265498D03*
X505728D03*
X500302D03*
X522939Y1265583D03*
X519131Y1265582D03*
X537023Y715259D03*
X528741Y812666D03*
X530453Y1265649D03*
X526725Y1265623D03*
X545741Y798666D03*
X552665Y844835D03*
X553383Y890391D03*
X570241Y803166D03*
Y824666D03*
X562231Y844813D03*
X577501Y816565D03*
X588001D03*
X577501Y823565D03*
X588001D03*
X613386Y1135426D03*
X617126D03*
X677586Y536517D03*
X681039Y1213969D03*
X748531Y1184048D03*
X780631Y1450177D03*
X787631Y1019429D03*
X791686D03*
X801082Y1451083D03*
X801998Y1471083D03*
X829852Y887022D03*
X829995Y920093D03*
X829494Y969724D03*
X835000Y756017D03*
X839000Y763017D03*
X835000Y774017D03*
X839000Y781017D03*
X835000Y792017D03*
X839000Y799017D03*
X835000Y810017D03*
X839000Y817017D03*
X836644Y858029D03*
X840381Y920586D03*
X844381D03*
X833898Y1448935D03*
X880054Y758201D03*
X874851D03*
X880054Y777215D03*
X874851Y777225D03*
X875916Y803407D03*
Y813557D03*
X879286Y908854D03*
X875286D03*
X894449Y600880D03*
X886610Y758200D03*
X885110Y777210D03*
X891916Y813557D03*
X895866Y820507D03*
X883866D03*
X888016D03*
X891916D03*
X883286Y908854D03*
X891286D03*
X887286D03*
X904393Y564718D03*
X908517D03*
X898815D03*
X909416Y813557D03*
X899916Y803407D03*
X899286Y908854D03*
X924143Y354908D03*
X918948Y354837D03*
X921790Y813557D03*
X913716Y803407D03*
X927286Y908854D03*
X923286D03*
X919286D03*
X915286D03*
X935124Y834473D03*
X941987Y854149D03*
X934944Y882078D03*
X931286Y908854D03*
X935286D03*
X952957Y919999D03*
X971648Y1221149D03*
X992000Y783517D03*
X985324Y1358823D03*
X999678Y327924D03*
X1021451Y317421D03*
X1025920Y317345D03*
X1013902Y890347D03*
X1029673Y317421D03*
X1051527Y1442528D03*
X1059448Y1435443D03*
X1074212Y1135426D03*
X1070472D03*
X1134673Y536517D03*
X1138125Y1213969D03*
X1160197Y794427D03*
X1173697D03*
X1187431Y878830D03*
Y871330D03*
X1183431D03*
X1187151Y923551D03*
Y930551D03*
X1205617Y1184048D03*
X1314604Y1270782D03*
X1326601Y331249D03*
X1333725Y331198D03*
X1319999Y1270782D03*
X1335936D03*
X1325478D03*
X1330582D03*
X1338500Y918017D03*
X1346083Y1122768D03*
X1342218Y1122805D03*
X1346362Y1270782D03*
X1351673D03*
X1341226D03*
X1364500Y816517D03*
X1360000D03*
X1355500D03*
X1364765Y1007283D03*
Y1014283D03*
X1356856Y1270782D03*
X1367828D03*
X1362308D03*
X1382667Y816388D03*
X1378000Y816517D03*
X1369000D03*
X1374500Y918017D03*
X1374551Y1023716D03*
X1370551D03*
X1378559Y1023697D03*
X1372152Y1270749D03*
X1380936Y1262872D03*
X1386122Y1262928D03*
X1391272Y1262894D03*
X1396296Y1262892D03*
X1407954Y1122979D03*
X1411829Y1122956D03*
X1411184Y1265627D03*
X1401428Y1262892D03*
X1415181Y1265627D03*
X1406916D03*
X1419451Y1265571D03*
X1440411Y1265627D03*
X1444381D03*
X1436439Y1265652D03*
X1467556Y890391D03*
X1493500Y940017D03*
X1510500Y926017D03*
X1528357Y971608D03*
X1517424Y972186D03*
X1527559Y1135426D03*
X1535000Y930517D03*
Y952017D03*
X1531299Y1135426D03*
X1591760Y536517D03*
X1595212Y1213969D03*
X1662704Y1184048D03*
X1817766Y1202417D03*
G54D64*
X408231Y1384896D03*
X418561Y1305317D03*
G54D73*
X721756Y-31826D03*
X841756Y-71006D03*
X1005256Y-41826D03*
X1075256Y-81006D03*
X1291756Y-41956D03*
X1331756Y-81006D03*
X1576256Y-42086D03*
X1586256Y-81006D03*
G54D37*
X79028Y883233D03*
X69028D03*
X71528D03*
X76528D03*
X74028D03*
X84028D03*
X81528D03*
X84028Y904833D03*
X76528D03*
X69028D03*
X81528D03*
X79028D03*
X74028D03*
X71528D03*
X86528Y883233D03*
Y904833D03*
X535968Y883233D03*
X525968D03*
X528468D03*
X533468D03*
X530968D03*
X538468D03*
X533468Y904833D03*
X525968D03*
X538468D03*
X535968D03*
X530968D03*
X528468D03*
X543468Y883233D03*
X540968D03*
Y904833D03*
X543468D03*
X993054Y883233D03*
X983054D03*
X985554D03*
X990554D03*
X988054D03*
X990554Y904833D03*
X983054D03*
X993054D03*
X988054D03*
X985554D03*
X1000554Y883233D03*
X998054D03*
X995554D03*
X998054Y904833D03*
X1000554D03*
X995554D03*
X1440141Y883233D03*
X1442641D03*
X1447641D03*
X1445141D03*
X1447641Y904833D03*
X1440141D03*
X1445141D03*
X1442641D03*
X1450141Y883233D03*
X1457641D03*
X1455141D03*
X1452641D03*
X1455141Y904833D03*
X1457641D03*
X1452641D03*
X1450141D03*
G54D46*
X195570Y1156430D03*
X191830D03*
X188090Y1144389D03*
Y1146489D03*
Y1151870D03*
Y1153970D03*
X195570Y1158530D03*
X188090Y1159050D03*
Y1156950D03*
X191830Y1158530D03*
X188090Y1172210D03*
Y1161850D03*
Y1163950D03*
X195570Y1171390D03*
X188090Y1168930D03*
Y1166830D03*
X191830Y1171390D03*
X188090Y1174310D03*
X195570Y1173490D03*
X191830D03*
X188100Y1185300D03*
Y1183200D03*
Y1178250D03*
Y1180350D03*
X197500Y1188451D03*
Y1186351D03*
X212401Y1133989D03*
Y1136089D03*
X204921Y1133989D03*
Y1136089D03*
X201181Y1133989D03*
Y1136089D03*
X203051Y1126508D03*
Y1128608D03*
X206791Y1126508D03*
Y1128608D03*
X214271Y1126508D03*
Y1128608D03*
X210531Y1126508D03*
Y1128608D03*
X208661Y1133989D03*
Y1136089D03*
X199311Y1126508D03*
Y1128608D03*
X208661Y1141469D03*
Y1143569D03*
X201181Y1141469D03*
Y1143569D03*
X204921Y1141469D03*
Y1143569D03*
X212401Y1141469D03*
Y1143569D03*
X199311Y1156430D03*
X208661Y1148949D03*
Y1151049D03*
X204921Y1148949D03*
Y1151049D03*
X201181Y1148949D03*
Y1151049D03*
X212401Y1148949D03*
Y1151049D03*
X210531Y1156430D03*
X214271D03*
X203051D03*
X206791D03*
X199311Y1158530D03*
X210531D03*
X214271D03*
X203051D03*
X206791D03*
X203051Y1171390D03*
X199311D03*
X206791D03*
X210531D03*
X214271D03*
X203051Y1173490D03*
X199311D03*
X206791D03*
X210531D03*
X214271D03*
X212401Y1188451D03*
Y1186351D03*
Y1180971D03*
Y1178871D03*
X208661Y1188451D03*
Y1186351D03*
Y1180971D03*
Y1178871D03*
X204921Y1180971D03*
Y1178871D03*
Y1188451D03*
Y1186351D03*
X201181Y1188451D03*
Y1186351D03*
Y1180971D03*
Y1178871D03*
X210315Y1203412D03*
Y1201312D03*
X202835Y1203412D03*
Y1201312D03*
X206575Y1203412D03*
Y1201312D03*
X214055Y1203412D03*
Y1201312D03*
X212401Y1195931D03*
Y1193831D03*
X208661Y1195931D03*
Y1193831D03*
X201181Y1195931D03*
Y1193831D03*
X204921Y1195931D03*
Y1193831D03*
X199095Y1203412D03*
Y1201312D03*
X231102Y1133989D03*
Y1136089D03*
X219881Y1133989D03*
Y1136089D03*
X229044Y1126508D03*
Y1128608D03*
X221751Y1126508D03*
Y1128608D03*
X225492Y1126508D03*
Y1128608D03*
X227362Y1133989D03*
Y1136089D03*
X223622Y1133989D03*
Y1136089D03*
X216141Y1133989D03*
Y1136089D03*
X218011Y1126508D03*
Y1128608D03*
X231102Y1141469D03*
Y1143569D03*
X227362Y1141469D03*
Y1143569D03*
X219881Y1141469D03*
Y1143569D03*
X223622Y1141469D03*
Y1143569D03*
X231102Y1148949D03*
Y1151049D03*
X219881Y1148949D03*
Y1151049D03*
X227362Y1148949D03*
Y1151049D03*
X223622Y1148949D03*
Y1151049D03*
X221752Y1156430D03*
X229232D03*
X225492D03*
X218011D03*
X216141Y1141469D03*
Y1143569D03*
Y1148949D03*
Y1151049D03*
X221752Y1158530D03*
X229232D03*
X225492D03*
X218011D03*
X229292Y1171390D03*
X225492D03*
X221752D03*
X218011D03*
X229292Y1173490D03*
X225492D03*
X221752D03*
X218011D03*
X223622Y1180971D03*
Y1178871D03*
X219881Y1188451D03*
Y1186351D03*
X223622Y1188451D03*
Y1186351D03*
X231102Y1180971D03*
Y1178871D03*
Y1188451D03*
Y1186351D03*
X227362Y1180971D03*
Y1178871D03*
Y1188451D03*
Y1186351D03*
X219881Y1180971D03*
Y1178871D03*
X216141Y1180971D03*
Y1178871D03*
Y1188451D03*
Y1186351D03*
X229016Y1203412D03*
Y1201312D03*
X231102Y1195931D03*
Y1193831D03*
X223622Y1195931D03*
Y1193831D03*
X227362Y1195931D03*
Y1193831D03*
X219881Y1195931D03*
Y1193831D03*
X225276Y1203412D03*
Y1201312D03*
X221535Y1203412D03*
Y1201312D03*
X217795Y1203412D03*
Y1201312D03*
X216141Y1195931D03*
Y1193831D03*
X238582Y1133989D03*
Y1136089D03*
X246062Y1133989D03*
Y1136089D03*
X244192Y1126508D03*
Y1128608D03*
X240452Y1126508D03*
Y1128608D03*
X236844Y1126508D03*
Y1128608D03*
X234842Y1133989D03*
Y1136089D03*
X242322Y1133989D03*
Y1136089D03*
Y1148949D03*
Y1151049D03*
X244192Y1156430D03*
X236712D03*
X240452D03*
X246062Y1148949D03*
Y1151049D03*
X234842Y1148949D03*
Y1151049D03*
X238582Y1148949D03*
Y1151049D03*
X246062Y1141469D03*
Y1143569D03*
X238582Y1141469D03*
Y1143569D03*
X234842Y1141469D03*
Y1143569D03*
X242322Y1141469D03*
Y1143569D03*
X244192Y1158530D03*
X236712D03*
X240452D03*
Y1171390D03*
X244192D03*
X236712D03*
X240452Y1173490D03*
X244192D03*
X236712D03*
X242322Y1180971D03*
Y1178871D03*
Y1188451D03*
Y1186351D03*
X246062Y1188451D03*
Y1186351D03*
X238582Y1180971D03*
Y1178871D03*
X234842Y1188451D03*
Y1186351D03*
X246062Y1180971D03*
Y1178871D03*
X238582Y1188451D03*
Y1186351D03*
X234842Y1180971D03*
Y1178871D03*
X246062Y1195931D03*
Y1193831D03*
X234842Y1195931D03*
Y1193831D03*
X240556Y1203412D03*
Y1201312D03*
X236816Y1203412D03*
Y1201312D03*
X244296Y1203412D03*
Y1201312D03*
X238582Y1195931D03*
Y1193831D03*
X242322Y1195931D03*
Y1193831D03*
X251673Y1126508D03*
Y1128608D03*
X255413Y1126508D03*
Y1128608D03*
X262893Y1126508D03*
Y1128608D03*
X261023Y1133989D03*
Y1136089D03*
X249803Y1133989D03*
Y1136089D03*
X257283Y1133989D03*
Y1136089D03*
X253543Y1133989D03*
Y1136089D03*
X259153Y1126508D03*
Y1128608D03*
X247933Y1126508D03*
Y1128608D03*
X259153Y1156430D03*
X261023Y1148949D03*
Y1151049D03*
X257283Y1148949D03*
Y1151049D03*
X262900Y1156430D03*
X249803Y1148949D03*
Y1151049D03*
X247932Y1156430D03*
X261023Y1141469D03*
Y1143569D03*
X257283Y1141469D03*
Y1143569D03*
X249803Y1141469D03*
Y1143569D03*
X253543Y1141469D03*
Y1143569D03*
Y1148949D03*
Y1151049D03*
X255413Y1156430D03*
X251673D03*
X259153Y1158530D03*
X262900D03*
X251673Y1171390D03*
X262893D03*
X259153D03*
X247933D03*
X255413D03*
X247932Y1158530D03*
X255413D03*
X251673D03*
Y1173490D03*
X262893D03*
X259153D03*
X247933D03*
X255413D03*
X249803Y1180971D03*
Y1178871D03*
Y1188451D03*
Y1186351D03*
X253543Y1180971D03*
Y1178871D03*
Y1188451D03*
Y1186351D03*
X261023Y1188451D03*
Y1186351D03*
X257283Y1188451D03*
Y1186351D03*
X261023Y1180971D03*
Y1178871D03*
X257283Y1180971D03*
Y1178871D03*
X262997Y1203412D03*
Y1201312D03*
X253543Y1195931D03*
Y1193831D03*
X259257Y1203412D03*
Y1201312D03*
X255517Y1203412D03*
Y1201312D03*
X251777Y1203412D03*
Y1201312D03*
X249803Y1195931D03*
Y1193831D03*
X261023Y1195931D03*
Y1193831D03*
X257283Y1195931D03*
Y1193831D03*
X248037Y1203412D03*
Y1201312D03*
X266633Y1126508D03*
Y1128608D03*
X264763Y1133989D03*
Y1136089D03*
Y1148949D03*
Y1151049D03*
Y1141469D03*
Y1143569D03*
Y1188451D03*
Y1186351D03*
Y1180971D03*
Y1178871D03*
Y1195931D03*
Y1193831D03*
X274114Y1196751D03*
Y1198851D03*
X266737Y1203412D03*
Y1201312D03*
X274114Y1204232D03*
Y1202132D03*
X395951Y1213350D03*
Y1215450D03*
X399246Y1213268D03*
Y1215368D03*
X406296Y1214005D03*
Y1216105D03*
X402595Y1213240D03*
Y1215340D03*
X506275Y1214181D03*
Y1216281D03*
X519673Y1214181D03*
Y1216281D03*
X531235Y1214210D03*
Y1216310D03*
X528129Y1214181D03*
Y1216281D03*
X645177Y1145209D03*
Y1147309D03*
Y1152350D03*
Y1154450D03*
X652657Y1156430D03*
X648917D03*
X652657Y1158530D03*
X645177Y1159350D03*
Y1157250D03*
X648917Y1158530D03*
X645177Y1172210D03*
Y1162150D03*
Y1164250D03*
X652657Y1171390D03*
X645177Y1169350D03*
Y1167250D03*
X648917Y1171390D03*
X645177Y1174310D03*
X652657Y1173490D03*
X648917D03*
X645177Y1185531D03*
Y1183431D03*
Y1178051D03*
Y1180151D03*
X658268Y1133989D03*
Y1136089D03*
X667618Y1126508D03*
Y1128608D03*
X663878Y1126508D03*
Y1128608D03*
X660138Y1126508D03*
Y1128608D03*
X665748Y1133989D03*
Y1136089D03*
X662008Y1133989D03*
Y1136089D03*
X669488Y1133989D03*
Y1136089D03*
X656398Y1126508D03*
Y1128608D03*
X665748Y1141469D03*
Y1143569D03*
X658268Y1141469D03*
Y1143569D03*
X662008Y1141469D03*
Y1143569D03*
X669488Y1141469D03*
Y1143569D03*
X656398Y1156430D03*
X663878D03*
X658268Y1148949D03*
Y1151049D03*
X665748Y1148949D03*
Y1151049D03*
X662008Y1148949D03*
Y1151049D03*
X669488Y1148949D03*
Y1151049D03*
X667618Y1156430D03*
X660138D03*
X656398Y1158530D03*
X663878D03*
X667618D03*
X660138D03*
Y1171390D03*
X663878D03*
X656398D03*
X667618D03*
X660138Y1173490D03*
X663878D03*
X656398D03*
X667618D03*
X658268Y1188451D03*
Y1186351D03*
X665748Y1180971D03*
Y1178871D03*
X662008Y1180971D03*
Y1178871D03*
Y1188451D03*
Y1186351D03*
X658268Y1180971D03*
Y1178871D03*
X669488Y1188451D03*
Y1186351D03*
Y1180971D03*
Y1178871D03*
X665748Y1188451D03*
Y1186351D03*
X654587Y1188451D03*
Y1186351D03*
X663878Y1203412D03*
Y1201312D03*
X667618Y1203412D03*
Y1201312D03*
X669488Y1195931D03*
Y1193831D03*
X665748Y1195931D03*
Y1193831D03*
X658268Y1195931D03*
Y1193831D03*
X662008Y1195931D03*
Y1193831D03*
X660138Y1203412D03*
Y1201312D03*
X656398Y1203412D03*
Y1201312D03*
X673228Y1133989D03*
Y1136089D03*
X684449Y1133989D03*
Y1136089D03*
X678838Y1126508D03*
Y1128608D03*
X675098Y1126508D03*
Y1128608D03*
X682579Y1126508D03*
Y1128608D03*
X680709Y1133989D03*
Y1136089D03*
X676968Y1133989D03*
Y1136089D03*
X671358Y1126508D03*
Y1128608D03*
X680709Y1141469D03*
Y1143569D03*
X684449Y1141469D03*
Y1143569D03*
X673228Y1141469D03*
Y1143569D03*
X676968Y1141469D03*
Y1143569D03*
X673228Y1148949D03*
Y1151049D03*
X682579Y1156430D03*
X671358D03*
X675098D03*
X678838D03*
X684449Y1148949D03*
Y1151049D03*
X680709Y1148949D03*
Y1151049D03*
X676968Y1148949D03*
Y1151049D03*
X682579Y1158530D03*
X671358D03*
X675098D03*
X678838D03*
X675098Y1171390D03*
X671358D03*
X682579D03*
X678838D03*
X675098Y1173490D03*
X671358D03*
X682579D03*
X678838D03*
X676968Y1188451D03*
Y1186351D03*
X673228Y1180971D03*
Y1178871D03*
X680709Y1188451D03*
Y1186351D03*
X673228Y1188451D03*
Y1186351D03*
X684449Y1180971D03*
Y1178871D03*
Y1188451D03*
Y1186351D03*
X676968Y1180971D03*
Y1178871D03*
X680709Y1180971D03*
Y1178871D03*
X675098Y1203412D03*
Y1201312D03*
X684449Y1195931D03*
Y1193831D03*
X680709Y1195931D03*
Y1193831D03*
X676968Y1195931D03*
Y1193831D03*
X673228Y1195931D03*
Y1193831D03*
X682579Y1203412D03*
Y1201312D03*
X678838Y1203412D03*
Y1201312D03*
X671358Y1203412D03*
Y1201312D03*
X701279Y1126508D03*
Y1128608D03*
X686131Y1126508D03*
Y1128608D03*
X695669Y1133989D03*
Y1136089D03*
X699409Y1133989D03*
Y1136089D03*
X691929Y1133989D03*
Y1136089D03*
X688189Y1133989D03*
Y1136089D03*
X697539Y1126508D03*
Y1128608D03*
X693931Y1126508D03*
Y1128608D03*
X699409Y1148949D03*
Y1151049D03*
X693799Y1156430D03*
X701279D03*
X697539D03*
X686319D03*
X688189Y1148949D03*
Y1151049D03*
X691929Y1148949D03*
Y1151049D03*
X695669Y1148949D03*
Y1151049D03*
X688189Y1141469D03*
Y1143569D03*
X695669Y1141469D03*
Y1143569D03*
X691929Y1141469D03*
Y1143569D03*
X699409Y1141469D03*
Y1143569D03*
X693799Y1158530D03*
X701279D03*
X697539D03*
X686319D03*
X697539Y1171390D03*
X701279D03*
X693799D03*
X686319D03*
X697539Y1173490D03*
X701279D03*
X693799D03*
X686319D03*
X699409Y1180971D03*
Y1178871D03*
X691929Y1180971D03*
Y1178871D03*
Y1188451D03*
Y1186351D03*
X695669Y1188451D03*
Y1186351D03*
X688189Y1180971D03*
Y1178871D03*
Y1188451D03*
Y1186351D03*
X699409Y1188451D03*
Y1186351D03*
X695669Y1180971D03*
Y1178871D03*
X688189Y1195931D03*
Y1193831D03*
X695669Y1195931D03*
Y1193831D03*
X691929Y1195931D03*
Y1193831D03*
X699409Y1195931D03*
Y1193831D03*
X693903Y1203412D03*
Y1201312D03*
X697539Y1203412D03*
Y1201312D03*
X701279Y1203412D03*
Y1201312D03*
X686103Y1203412D03*
Y1201312D03*
X703149Y1133989D03*
Y1136089D03*
X705020Y1126508D03*
Y1128608D03*
X712500Y1126508D03*
Y1128608D03*
X708760Y1126508D03*
Y1128608D03*
X718110Y1133989D03*
Y1136089D03*
X716240Y1126508D03*
Y1128608D03*
X710630Y1133989D03*
Y1136089D03*
X714370Y1133989D03*
Y1136089D03*
X706890Y1133989D03*
Y1136089D03*
X703149Y1141469D03*
Y1143569D03*
X705020Y1156430D03*
X703149Y1148949D03*
Y1151049D03*
X706890Y1141469D03*
Y1143569D03*
X710630Y1141469D03*
Y1143569D03*
X718110Y1141469D03*
Y1143569D03*
X714370Y1141469D03*
Y1143569D03*
X716240Y1156430D03*
X708760D03*
X712500D03*
X718110Y1148949D03*
Y1151049D03*
X710630Y1148949D03*
Y1151049D03*
X706890Y1148949D03*
Y1151049D03*
X714370Y1148949D03*
Y1151049D03*
X712500Y1171390D03*
X705020Y1158530D03*
X716240D03*
X708760D03*
X712500D03*
X716240Y1171390D03*
X708760D03*
X705020D03*
X712500Y1173490D03*
X706890Y1188451D03*
Y1186351D03*
X718110Y1180971D03*
Y1178871D03*
Y1188451D03*
Y1186351D03*
X714370Y1180971D03*
Y1178871D03*
Y1188451D03*
Y1186351D03*
X710630Y1180971D03*
Y1178871D03*
X706890Y1180971D03*
Y1178871D03*
X710630Y1188451D03*
Y1186351D03*
X703149Y1180971D03*
Y1178871D03*
Y1188451D03*
Y1186351D03*
X716240Y1173490D03*
X708760D03*
X705020D03*
X706890Y1195931D03*
Y1193831D03*
X708760Y1203412D03*
Y1201312D03*
X712500Y1203412D03*
Y1201312D03*
X710630Y1195931D03*
Y1193831D03*
X705020Y1203412D03*
Y1201312D03*
X714370Y1195931D03*
Y1193831D03*
X716240Y1203412D03*
Y1201312D03*
X718110Y1195931D03*
Y1193831D03*
X703149Y1195931D03*
Y1193831D03*
X723720Y1126508D03*
Y1128608D03*
X721850Y1133989D03*
Y1136089D03*
X719980Y1126508D03*
Y1128608D03*
X721850Y1141469D03*
Y1143569D03*
Y1148949D03*
Y1151049D03*
X719980Y1156430D03*
Y1171390D03*
Y1158530D03*
Y1173490D03*
X721850Y1180971D03*
Y1178871D03*
Y1188451D03*
Y1186351D03*
Y1195931D03*
Y1193831D03*
X719980Y1203412D03*
Y1201312D03*
X723720Y1203412D03*
Y1201312D03*
X731201Y1196751D03*
Y1198851D03*
Y1204232D03*
Y1202132D03*
X873257Y1103056D03*
Y1100956D03*
X876877Y1103058D03*
Y1100958D03*
X870004Y1103014D03*
Y1100914D03*
X951421Y1098057D03*
Y1095957D03*
X1106003Y1156430D03*
X1102263Y1151870D03*
Y1153970D03*
Y1144389D03*
Y1146489D03*
X1106003Y1171390D03*
X1102263Y1172210D03*
Y1168930D03*
Y1166830D03*
Y1161850D03*
Y1163950D03*
Y1159050D03*
Y1156950D03*
X1106003Y1158530D03*
X1102273Y1185300D03*
Y1183200D03*
Y1178250D03*
Y1180350D03*
X1106003Y1173490D03*
X1102263Y1174310D03*
X1122834Y1133989D03*
Y1136089D03*
X1119094Y1133989D03*
Y1136089D03*
X1115354Y1133989D03*
Y1136089D03*
X1120964Y1126508D03*
Y1128608D03*
X1117224Y1126508D03*
Y1128608D03*
X1113484Y1126508D03*
Y1128608D03*
X1120964Y1156430D03*
X1117224D03*
X1113484D03*
X1109743D03*
X1122834Y1148949D03*
Y1151049D03*
X1119094Y1148949D03*
Y1151049D03*
X1115354Y1148949D03*
Y1151049D03*
X1122834Y1141469D03*
Y1143569D03*
X1115354Y1141469D03*
Y1143569D03*
X1119094Y1141469D03*
Y1143569D03*
X1120964Y1171390D03*
X1117224D03*
X1113484D03*
X1109743D03*
X1120964Y1158530D03*
X1117224D03*
X1113484D03*
X1109743D03*
X1122834Y1188451D03*
Y1186351D03*
X1119094Y1188451D03*
Y1186351D03*
X1115354Y1188451D03*
Y1186351D03*
X1111673Y1188451D03*
Y1186351D03*
X1122834Y1180971D03*
Y1178871D03*
X1119094Y1180971D03*
Y1178871D03*
X1115354Y1180971D03*
Y1178871D03*
X1120964Y1173490D03*
X1117224D03*
X1113484D03*
X1109743D03*
X1124488Y1203412D03*
Y1201312D03*
X1120748Y1203412D03*
Y1201312D03*
X1117008Y1203412D03*
Y1201312D03*
X1113268Y1203412D03*
Y1201312D03*
X1122834Y1195931D03*
Y1193831D03*
X1119094Y1195931D03*
Y1193831D03*
X1115354Y1195931D03*
Y1193831D03*
X1137795Y1133989D03*
Y1136089D03*
X1134054Y1133989D03*
Y1136089D03*
X1130314Y1133989D03*
Y1136089D03*
X1126574Y1133989D03*
Y1136089D03*
X1139665Y1126508D03*
Y1128608D03*
X1135924Y1126508D03*
Y1128608D03*
X1132184Y1126508D03*
Y1128608D03*
X1128444Y1126508D03*
Y1128608D03*
X1124704Y1126508D03*
Y1128608D03*
X1139665Y1156430D03*
X1135925D03*
X1132184D03*
X1128444D03*
X1124704D03*
X1137795Y1148949D03*
Y1151049D03*
X1134054Y1148949D03*
Y1151049D03*
X1130314Y1148949D03*
Y1151049D03*
X1126574Y1148949D03*
Y1151049D03*
X1137795Y1141469D03*
Y1143569D03*
X1134054Y1141469D03*
Y1143569D03*
X1130314Y1141469D03*
Y1143569D03*
X1126574Y1141469D03*
Y1143569D03*
X1139665Y1171390D03*
X1135925D03*
X1132184D03*
X1128444D03*
X1124704D03*
X1139665Y1158530D03*
X1135925D03*
X1132184D03*
X1128444D03*
X1124704D03*
X1137795Y1188451D03*
Y1186351D03*
X1134054Y1188451D03*
Y1186351D03*
X1130314Y1188451D03*
Y1186351D03*
X1126574Y1188451D03*
Y1186351D03*
X1137795Y1180971D03*
Y1178871D03*
X1134054Y1180971D03*
Y1178871D03*
X1130314Y1180971D03*
Y1178871D03*
X1126574Y1180971D03*
Y1178871D03*
X1139665Y1173490D03*
X1135925D03*
X1132184D03*
X1128444D03*
X1124704D03*
X1139449Y1203412D03*
Y1201312D03*
X1135708Y1203412D03*
Y1201312D03*
X1131968Y1203412D03*
Y1201312D03*
X1128228Y1203412D03*
Y1201312D03*
X1137795Y1195931D03*
Y1193831D03*
X1134054Y1195931D03*
Y1193831D03*
X1130314Y1195931D03*
Y1193831D03*
X1126574Y1195931D03*
Y1193831D03*
X1156495Y1133989D03*
Y1136089D03*
X1152755Y1133989D03*
Y1136089D03*
X1149015Y1133989D03*
Y1136089D03*
X1145275Y1133989D03*
Y1136089D03*
X1141535Y1133989D03*
Y1136089D03*
X1154625Y1126508D03*
Y1128608D03*
X1150885Y1126508D03*
Y1128608D03*
X1143405Y1126508D03*
Y1128608D03*
X1154625Y1156430D03*
X1150885D03*
X1143405D03*
X1156495Y1148949D03*
Y1151049D03*
X1152755Y1148949D03*
Y1151049D03*
X1149015Y1148949D03*
Y1151049D03*
X1145275Y1148949D03*
Y1151049D03*
X1141535Y1148949D03*
Y1151049D03*
X1152755Y1141469D03*
Y1143569D03*
X1156495Y1141469D03*
Y1143569D03*
X1149015Y1141469D03*
Y1143569D03*
X1145275Y1141469D03*
Y1143569D03*
X1141535Y1141469D03*
Y1143569D03*
X1154625Y1171390D03*
X1150885D03*
X1143465D03*
X1154625Y1158530D03*
X1150885D03*
X1143405D03*
X1156495Y1188451D03*
Y1186351D03*
X1152755Y1188451D03*
Y1186351D03*
X1149015Y1188451D03*
Y1186351D03*
X1145275Y1188451D03*
Y1186351D03*
X1141535Y1188451D03*
Y1186351D03*
X1156495Y1180971D03*
Y1178871D03*
X1152755Y1180971D03*
Y1178871D03*
X1149015Y1180971D03*
Y1178871D03*
X1145275Y1180971D03*
Y1178871D03*
X1141535Y1180971D03*
Y1178871D03*
X1154625Y1173490D03*
X1150885D03*
X1143465D03*
X1154729Y1203412D03*
Y1201312D03*
X1150989Y1203412D03*
Y1201312D03*
X1143189Y1203412D03*
Y1201312D03*
X1156495Y1195931D03*
Y1193831D03*
X1152755Y1195931D03*
Y1193831D03*
X1149015Y1195931D03*
Y1193831D03*
X1145275Y1195931D03*
Y1193831D03*
X1141535Y1195931D03*
Y1193831D03*
X1171456Y1133989D03*
Y1136089D03*
X1167716Y1133989D03*
Y1136089D03*
X1163976Y1133989D03*
Y1136089D03*
X1160235Y1133989D03*
Y1136089D03*
X1169586Y1126508D03*
Y1128608D03*
X1165846Y1126508D03*
Y1128608D03*
X1162106Y1126508D03*
Y1128608D03*
X1158365Y1126508D03*
Y1128608D03*
X1169586Y1156430D03*
X1165846D03*
X1162105D03*
X1158365D03*
X1171456Y1148949D03*
Y1151049D03*
X1167716Y1148949D03*
Y1151049D03*
X1163976Y1148949D03*
Y1151049D03*
X1160235Y1148949D03*
Y1151049D03*
X1171456Y1141469D03*
Y1143569D03*
X1167716Y1141469D03*
Y1143569D03*
X1160235Y1141469D03*
Y1143569D03*
X1163976Y1141469D03*
Y1143569D03*
X1169586Y1171390D03*
X1165846D03*
X1162106D03*
X1158365D03*
X1169586Y1158530D03*
X1165846D03*
X1162105D03*
X1158365D03*
X1171456Y1188451D03*
Y1186351D03*
X1167716Y1188451D03*
Y1186351D03*
X1163976Y1188451D03*
Y1186351D03*
X1160235Y1188451D03*
Y1186351D03*
X1171456Y1180971D03*
Y1178871D03*
X1167716Y1180971D03*
Y1178871D03*
X1163976Y1180971D03*
Y1178871D03*
X1160235Y1180971D03*
Y1178871D03*
X1169586Y1173490D03*
X1165846D03*
X1162106D03*
X1158365D03*
X1169690Y1203412D03*
Y1201312D03*
X1165950Y1203412D03*
Y1201312D03*
X1162210Y1203412D03*
Y1201312D03*
X1158469Y1203412D03*
Y1201312D03*
X1171456Y1195931D03*
Y1193831D03*
X1167716Y1195931D03*
Y1193831D03*
X1163976Y1195931D03*
Y1193831D03*
X1160235Y1195931D03*
Y1193831D03*
X1178936Y1133989D03*
Y1136089D03*
X1175196Y1133989D03*
Y1136089D03*
X1180806Y1126508D03*
Y1128608D03*
X1177066Y1126508D03*
Y1128608D03*
X1173326Y1126508D03*
Y1128608D03*
X1177073Y1156430D03*
X1173326D03*
X1178936Y1148949D03*
Y1151049D03*
X1175196Y1148949D03*
Y1151049D03*
X1178936Y1141469D03*
Y1143569D03*
X1175196Y1141469D03*
Y1143569D03*
X1177066Y1171390D03*
X1173326D03*
X1177073Y1158530D03*
X1173326D03*
X1178936Y1188451D03*
Y1186351D03*
X1175196Y1188451D03*
Y1186351D03*
X1178936Y1180971D03*
Y1178871D03*
X1175196Y1180971D03*
Y1178871D03*
X1177066Y1173490D03*
X1173326D03*
X1188287Y1204232D03*
Y1202132D03*
Y1196751D03*
Y1198851D03*
X1180910Y1203412D03*
Y1201312D03*
X1177170Y1203412D03*
Y1201312D03*
X1173430Y1203412D03*
Y1201312D03*
X1178936Y1195931D03*
Y1193831D03*
X1175196Y1195931D03*
Y1193831D03*
X1312962Y1213613D03*
Y1215713D03*
X1310791Y1275725D03*
Y1273625D03*
X1333734Y1214501D03*
Y1216601D03*
X1340056Y1214492D03*
Y1216592D03*
X1336913Y1214487D03*
Y1216587D03*
X1420941Y1214217D03*
Y1216317D03*
X1445901Y1214246D03*
Y1216346D03*
X1442795Y1214217D03*
Y1216317D03*
X1434339Y1214217D03*
Y1216317D03*
X1559350Y1151870D03*
Y1153970D03*
Y1144389D03*
Y1146489D03*
X1563090Y1156430D03*
X1559350Y1172210D03*
Y1168930D03*
Y1166830D03*
Y1161850D03*
Y1163950D03*
Y1159050D03*
Y1156950D03*
X1563090Y1171390D03*
Y1158530D03*
X1559360Y1185300D03*
Y1183200D03*
Y1178250D03*
Y1180350D03*
X1559350Y1174310D03*
X1563090Y1173490D03*
X1570571Y1126508D03*
Y1128608D03*
X1572441Y1133989D03*
Y1136089D03*
X1574311Y1126508D03*
Y1128608D03*
X1578051Y1126508D03*
Y1128608D03*
X1576181Y1133989D03*
Y1136089D03*
X1572441Y1141469D03*
Y1143569D03*
Y1148949D03*
Y1151049D03*
X1566830Y1156430D03*
X1570571D03*
X1576181Y1141469D03*
Y1143569D03*
Y1148949D03*
Y1151049D03*
X1574311Y1156430D03*
X1578051D03*
X1566830Y1171390D03*
X1570571D03*
X1574311D03*
X1578051D03*
X1566830Y1158530D03*
X1570571D03*
X1574311D03*
X1578051D03*
X1572441Y1180971D03*
Y1178871D03*
X1568760Y1188451D03*
Y1186351D03*
X1572441Y1188451D03*
Y1186351D03*
X1576181Y1180971D03*
Y1178871D03*
Y1188451D03*
Y1186351D03*
X1566830Y1173490D03*
X1570571D03*
X1574311D03*
X1578051D03*
X1572441Y1195931D03*
Y1193831D03*
X1570355Y1203412D03*
Y1201312D03*
X1576181Y1195931D03*
Y1193831D03*
X1574095Y1203412D03*
Y1201312D03*
X1577835Y1203412D03*
Y1201312D03*
X1581791Y1126508D03*
Y1128608D03*
X1585531Y1126508D03*
Y1128608D03*
X1589271Y1126508D03*
Y1128608D03*
X1579921Y1133989D03*
Y1136089D03*
X1583661Y1133989D03*
Y1136089D03*
X1587401Y1133989D03*
Y1136089D03*
X1593011Y1126508D03*
Y1128608D03*
X1591141Y1133989D03*
Y1136089D03*
X1594882Y1133989D03*
Y1136089D03*
X1579921Y1141469D03*
Y1143569D03*
X1583661Y1141469D03*
Y1143569D03*
X1587401Y1141469D03*
Y1143569D03*
X1579921Y1148949D03*
Y1151049D03*
X1583661Y1148949D03*
Y1151049D03*
X1587401Y1148949D03*
Y1151049D03*
X1581791Y1156430D03*
X1585531D03*
X1589271D03*
X1591141Y1141469D03*
Y1143569D03*
X1594882Y1141469D03*
Y1143569D03*
X1591141Y1148949D03*
Y1151049D03*
X1594882Y1148949D03*
Y1151049D03*
X1593012Y1156430D03*
X1581791Y1171390D03*
X1585531D03*
X1589271D03*
X1593012D03*
X1581791Y1158530D03*
X1585531D03*
X1589271D03*
X1593012D03*
X1579921Y1180971D03*
Y1178871D03*
X1583661Y1180971D03*
Y1178871D03*
X1587401Y1180971D03*
Y1178871D03*
X1579921Y1188451D03*
Y1186351D03*
X1583661Y1188451D03*
Y1186351D03*
X1587401Y1188451D03*
Y1186351D03*
X1591141Y1180971D03*
Y1178871D03*
X1594882Y1180971D03*
Y1178871D03*
X1591141Y1188451D03*
Y1186351D03*
X1594882Y1188451D03*
Y1186351D03*
X1581791Y1173490D03*
X1585531D03*
X1589271D03*
X1593012D03*
X1579921Y1195931D03*
Y1193831D03*
X1583661Y1195931D03*
Y1193831D03*
X1587401Y1195931D03*
Y1193831D03*
X1581575Y1203412D03*
Y1201312D03*
X1585315Y1203412D03*
Y1201312D03*
X1589055Y1203412D03*
Y1201312D03*
X1591141Y1195931D03*
Y1193831D03*
X1594882Y1195931D03*
Y1193831D03*
X1592795Y1203412D03*
Y1201312D03*
X1596752Y1126508D03*
Y1128608D03*
X1600492Y1126508D03*
Y1128608D03*
X1598622Y1133989D03*
Y1136089D03*
X1602362Y1133989D03*
Y1136089D03*
X1606102Y1133989D03*
Y1136089D03*
X1607972Y1126508D03*
Y1128608D03*
X1611712Y1126508D03*
Y1128608D03*
X1609842Y1133989D03*
Y1136089D03*
X1598622Y1141469D03*
Y1143569D03*
X1602362Y1141469D03*
Y1143569D03*
X1606102Y1141469D03*
Y1143569D03*
X1598622Y1148949D03*
Y1151049D03*
X1602362Y1148949D03*
Y1151049D03*
X1606102Y1148949D03*
Y1151049D03*
X1596752Y1156430D03*
X1600492D03*
X1609842Y1141469D03*
Y1143569D03*
Y1148949D03*
Y1151049D03*
X1607972Y1156430D03*
X1611712D03*
X1596752Y1171390D03*
X1600552D03*
X1607972D03*
X1611712D03*
X1596752Y1158530D03*
X1600492D03*
X1607972D03*
X1611712D03*
X1598622Y1180971D03*
Y1178871D03*
X1602362Y1180971D03*
Y1178871D03*
X1606102Y1180971D03*
Y1178871D03*
X1598622Y1188451D03*
Y1186351D03*
X1602362Y1188451D03*
Y1186351D03*
X1606102Y1188451D03*
Y1186351D03*
X1609842Y1180971D03*
Y1178871D03*
Y1188451D03*
Y1186351D03*
X1596752Y1173490D03*
X1600552D03*
X1607972D03*
X1611712D03*
X1598622Y1195931D03*
Y1193831D03*
X1602362Y1195931D03*
Y1193831D03*
X1606102Y1195931D03*
Y1193831D03*
X1596536Y1203412D03*
Y1201312D03*
X1600276Y1203412D03*
Y1201312D03*
X1609842Y1195931D03*
Y1193831D03*
X1608076Y1203412D03*
Y1201312D03*
X1611816Y1203412D03*
Y1201312D03*
X1615452Y1126508D03*
Y1128608D03*
X1619193Y1126508D03*
Y1128608D03*
X1613582Y1133989D03*
Y1136089D03*
X1617322Y1133989D03*
Y1136089D03*
X1621063Y1133989D03*
Y1136089D03*
X1622933Y1126508D03*
Y1128608D03*
X1626673Y1126508D03*
Y1128608D03*
X1624803Y1133989D03*
Y1136089D03*
X1613582Y1141469D03*
Y1143569D03*
X1617322Y1141469D03*
Y1143569D03*
X1621063Y1141469D03*
Y1143569D03*
X1613582Y1148949D03*
Y1151049D03*
X1617322Y1148949D03*
Y1151049D03*
X1621063Y1148949D03*
Y1151049D03*
X1615452Y1156430D03*
X1619192D03*
X1624803Y1141469D03*
Y1143569D03*
Y1148949D03*
Y1151049D03*
X1622933Y1156430D03*
X1626673D03*
X1615452Y1171390D03*
X1619193D03*
X1622933D03*
X1626673D03*
X1615452Y1158530D03*
X1619192D03*
X1622933D03*
X1626673D03*
X1613582Y1180971D03*
Y1178871D03*
X1617322Y1180971D03*
Y1178871D03*
X1621063Y1180971D03*
Y1178871D03*
X1613582Y1188451D03*
Y1186351D03*
X1617322Y1188451D03*
Y1186351D03*
X1621063Y1188451D03*
Y1186351D03*
X1624803Y1180971D03*
Y1178871D03*
Y1188451D03*
Y1186351D03*
X1615452Y1173490D03*
X1619193D03*
X1622933D03*
X1626673D03*
X1613582Y1195931D03*
Y1193831D03*
X1617322Y1195931D03*
Y1193831D03*
X1621063Y1195931D03*
Y1193831D03*
X1615556Y1203412D03*
Y1201312D03*
X1619297Y1203412D03*
Y1201312D03*
X1624803Y1195931D03*
Y1193831D03*
X1623037Y1203412D03*
Y1201312D03*
X1626777Y1203412D03*
Y1201312D03*
X1630413Y1126508D03*
Y1128608D03*
X1634153Y1126508D03*
Y1128608D03*
X1637893Y1126508D03*
Y1128608D03*
X1628543Y1133989D03*
Y1136089D03*
X1632283Y1133989D03*
Y1136089D03*
X1636023Y1133989D03*
Y1136089D03*
X1628543Y1141469D03*
Y1143569D03*
X1632283Y1141469D03*
Y1143569D03*
X1636023Y1141469D03*
Y1143569D03*
X1628543Y1148949D03*
Y1151049D03*
X1632283Y1148949D03*
Y1151049D03*
X1636023Y1148949D03*
Y1151049D03*
X1630413Y1156430D03*
X1634160D03*
X1630413Y1171390D03*
X1634153D03*
X1630413Y1158530D03*
X1634160D03*
X1628543Y1180971D03*
Y1178871D03*
X1632283Y1180971D03*
Y1178871D03*
X1636023Y1180971D03*
Y1178871D03*
X1628543Y1188451D03*
Y1186351D03*
X1632283Y1188451D03*
Y1186351D03*
X1636023Y1188451D03*
Y1186351D03*
X1630413Y1173490D03*
X1634153D03*
X1628543Y1195931D03*
Y1193831D03*
X1632283Y1195931D03*
Y1193831D03*
X1636023Y1195931D03*
Y1193831D03*
X1630517Y1203412D03*
Y1201312D03*
X1634257Y1203412D03*
Y1201312D03*
X1637997Y1203412D03*
Y1201312D03*
X1645374Y1196751D03*
Y1198851D03*
Y1204232D03*
Y1202132D03*
G54D82*
X891031Y694107D03*
X893984Y696075D03*
X891031D03*
X893984Y692138D03*
Y694107D03*
G54D91*
X1030635Y754546D03*
Y764546D03*
Y774546D03*
Y784546D03*
Y794546D03*
Y804546D03*
Y814546D03*
G54D55*
X251694Y1436156D03*
X237390Y1437236D03*
X392745Y1515756D03*
G54D29*
X25807Y1529931D03*
Y1522774D03*
X60657Y847627D03*
X56904Y897500D03*
X59010Y1511735D03*
X60496Y1525714D03*
X60520Y1518596D03*
X60470Y1531804D03*
X87130Y681800D03*
X95806Y875194D03*
Y879194D03*
X115610Y892845D03*
Y884845D03*
Y888845D03*
X156222Y1148530D03*
X156681Y1164560D03*
X156466Y1160650D03*
X156681Y1169100D03*
X180117Y550400D03*
Y554400D03*
X197903Y544967D03*
X190903D03*
X193617Y618400D03*
X258661Y438323D03*
X248058Y427017D03*
X248026Y435029D03*
Y431029D03*
X279189Y467367D03*
X281017Y384500D03*
X303800Y377912D03*
Y389912D03*
Y381912D03*
Y385912D03*
Y393924D03*
Y397912D03*
Y401924D03*
Y405924D03*
Y409924D03*
X392828Y1299275D03*
Y1303275D03*
X389672Y1311289D03*
Y1315289D03*
X385495Y1384722D03*
Y1388722D03*
X397034Y1540700D03*
Y1535200D03*
Y1547200D03*
X417666Y343005D03*
X418087Y334523D03*
X418597Y1111226D03*
X422524Y1288843D03*
X425470Y1320684D03*
X422225Y1370972D03*
X428210Y349696D03*
X435340Y1309865D03*
X430099Y1398800D03*
X430075Y1394934D03*
X456302Y1002180D03*
X450618Y1111226D03*
X455715Y1193471D03*
X445423Y1301545D03*
Y1297045D03*
Y1305545D03*
X459402Y1007325D03*
X464608Y1014566D03*
X468389Y1197471D03*
X488010Y795025D03*
X484069Y1111177D03*
X503403Y704755D03*
X506258Y796149D03*
X497124Y790275D03*
X523046Y713581D03*
X512453Y799973D03*
Y811973D03*
Y803973D03*
Y807973D03*
X522221Y831027D03*
X522258Y840649D03*
Y836149D03*
X521901Y849830D03*
X513844Y897500D03*
X516327Y1111272D03*
X533296Y708711D03*
X529221Y831027D03*
X529258Y836149D03*
Y840649D03*
X528901Y849830D03*
X552221Y796389D03*
X552746Y879194D03*
Y875194D03*
X572550Y888845D03*
Y884845D03*
Y892845D03*
X577917Y961804D03*
X613309Y1148530D03*
X613553Y1160650D03*
X613768Y1169100D03*
Y1164560D03*
X637203Y550400D03*
Y554400D03*
X647989Y544967D03*
X650703Y618400D03*
X654989Y544967D03*
X697036Y762971D03*
Y756971D03*
X697022Y780659D03*
Y775159D03*
X715747Y438323D03*
X725966Y442606D03*
Y446606D03*
X738103Y384500D03*
X736275Y467367D03*
X760886Y377912D03*
Y389912D03*
Y381912D03*
Y385912D03*
Y393924D03*
Y397912D03*
Y401924D03*
Y405924D03*
Y409924D03*
X799361Y1460979D03*
X813911Y872812D03*
Y876605D03*
X803136Y1425152D03*
X803361Y1436240D03*
X828241Y859484D03*
X831404Y1463690D03*
X842826Y835459D03*
Y839459D03*
X840781Y843490D03*
X840378Y855397D03*
X842826Y851459D03*
X842740Y875476D03*
X839975Y879459D03*
Y883459D03*
X839881Y891503D03*
X839882Y887490D03*
X861908Y388245D03*
X853776Y847459D03*
Y835459D03*
Y839459D03*
Y843459D03*
Y855459D03*
X853823Y851924D03*
X886568Y571532D03*
X887719Y577288D03*
X887776Y585773D03*
X883748Y1460847D03*
X912167Y360583D03*
X912398Y365893D03*
X900663Y888478D03*
X916990Y312228D03*
X923635Y1379411D03*
X923662Y1383264D03*
X923688Y1387039D03*
X923716Y1390841D03*
X933988Y1371951D03*
X934062Y1375878D03*
X939030Y1443901D03*
X971350Y897500D03*
X965075Y1444474D03*
X990717Y1369200D03*
Y1373400D03*
Y1385200D03*
Y1394200D03*
Y1389200D03*
X990688Y1398271D03*
X987260Y1444240D03*
X1007775Y327510D03*
Y323386D03*
Y333088D03*
Y339880D03*
X1002518Y801475D03*
X1006522Y816957D03*
X1009832Y875194D03*
Y879194D03*
X1011371Y1444512D03*
X1029636Y892845D03*
Y884845D03*
Y888845D03*
X1037037Y1444596D03*
X1043937Y337454D03*
X1070395Y1148530D03*
X1070854Y1164560D03*
Y1169100D03*
X1070639Y1160650D03*
X1088807Y1533457D03*
X1094290Y550400D03*
Y554400D03*
X1105076Y544967D03*
X1107790Y618400D03*
X1112076Y544967D03*
X1152534Y788431D03*
X1146002Y797142D03*
Y810142D03*
X1162231Y427017D03*
X1162199Y431029D03*
Y435029D03*
X1172834Y438323D03*
X1183053Y442606D03*
Y446606D03*
X1176669Y888899D03*
X1195190Y384500D03*
X1193362Y467367D03*
X1217973Y377912D03*
Y389912D03*
Y381912D03*
Y385912D03*
Y393924D03*
Y397912D03*
Y401924D03*
Y405924D03*
Y409924D03*
X1260747Y327257D03*
X1267654D03*
X1276517Y330500D03*
Y334500D03*
X1296517Y871800D03*
Y875800D03*
Y891800D03*
X1287981Y881802D03*
X1320672Y337615D03*
X1320287Y346026D03*
X1330795Y352788D03*
X1332547Y1111198D03*
X1364758D03*
X1382950Y569000D03*
Y565000D03*
Y615500D03*
Y611500D03*
X1373576Y1007325D03*
X1370476Y1002180D03*
X1378782Y1014566D03*
X1382563Y1197471D03*
X1369889Y1193471D03*
X1394534Y984037D03*
X1398205Y1111258D03*
X1408832Y992861D03*
X1407917Y1423700D03*
X1428017Y897500D03*
X1430448Y1111197D03*
X1440517Y927000D03*
X1466919Y879194D03*
Y875194D03*
X1471017Y923500D03*
X1477212Y927324D03*
Y931324D03*
Y939324D03*
Y935324D03*
X1497580Y876339D03*
X1487353Y891615D03*
X1493980Y958378D03*
X1486980D03*
X1494017Y963500D03*
X1487017D03*
X1494017Y968000D03*
X1487017D03*
X1486660Y977181D03*
X1493660D03*
X1516980Y923740D03*
X1523017Y943000D03*
X1516017D03*
X1527482Y1148530D03*
X1527726Y1160650D03*
X1527941Y1169100D03*
Y1164560D03*
X1551377Y550400D03*
Y554400D03*
X1562163Y544967D03*
X1548240Y1418847D03*
X1557239Y1418806D03*
X1569163Y544967D03*
X1564877Y618400D03*
X1585527Y341787D03*
Y337787D03*
X1619318Y427017D03*
X1619286Y431029D03*
Y435029D03*
X1629921Y438323D03*
X1652277Y384500D03*
X1650449Y467367D03*
X1675060Y377912D03*
Y389912D03*
Y381912D03*
Y385912D03*
Y393924D03*
Y397912D03*
Y401924D03*
Y405924D03*
Y409924D03*
G54D83*
X895542Y859465D03*
X892392D03*
X895542Y856316D03*
X892392D03*
X895542Y862615D03*
X892392D03*
X895542Y868914D03*
X892392D03*
X910029Y836875D03*
X906879D03*
X920739Y846867D03*
X917589D03*
X920739Y853166D03*
X917589D03*
X945122Y860671D03*
X945030Y864721D03*
X945147Y868168D03*
X948272Y860671D03*
X948180Y864721D03*
X948297Y868168D03*
X1318541Y863128D03*
X1321691D03*
X1349976Y840894D03*
X1346826D03*
X1359425Y878689D03*
X1356275D03*
X1378266Y844021D03*
X1375116D03*
X1381461Y885021D03*
X1378311D03*
X1393970Y862829D03*
X1390820D03*
X1393947Y866620D03*
X1390797D03*
X1393001Y871018D03*
X1389851D03*
X1392988Y876204D03*
X1389838D03*
G54D56*
X269682Y451628D03*
X275588Y458714D03*
X269682D03*
X275588Y451628D03*
X726768D03*
X732674Y458714D03*
X726768D03*
X732674Y451628D03*
X1183855D03*
X1189761Y458714D03*
X1183855D03*
X1189761Y451628D03*
X1640942D03*
Y458714D03*
X1646848D03*
Y451628D03*
G54D47*
X197247Y1544069D03*
G54D65*
X401341Y1375546D03*
X403310D03*
X405278D03*
X407247D03*
X409215D03*
X401341Y1394246D03*
X403310D03*
X405278D03*
X407247D03*
X409215D03*
X413640Y1295967D03*
X411671D03*
X419545D03*
X421514D03*
X423482D03*
X425451D03*
X415608D03*
X417577D03*
X425451Y1314667D03*
X413640D03*
X423482D03*
X419545D03*
X411671D03*
X421514D03*
X417577D03*
X415608D03*
X411184Y1375546D03*
X413152D03*
X415121D03*
X411184Y1394246D03*
X413152D03*
X415121D03*
G54D74*
X725006Y-30842D03*
Y-32810D03*
X845006Y-70022D03*
Y-71990D03*
X949942Y-32782D03*
Y-30814D03*
X974786Y-71962D03*
Y-69994D03*
X1008506Y-40842D03*
Y-42810D03*
X1078506Y-80022D03*
Y-81990D03*
X1228086Y-81962D03*
Y-79994D03*
X1233442Y-42912D03*
Y-40944D03*
X1295006Y-40972D03*
Y-42940D03*
X1335006Y-80022D03*
Y-81990D03*
X1484586Y-81962D03*
Y-79994D03*
X1519942Y-43042D03*
Y-41074D03*
X1579506Y-41102D03*
Y-43070D03*
X1589506Y-80022D03*
Y-81990D03*
X1739086Y-81962D03*
Y-79994D03*
X1804442Y-43172D03*
Y-41204D03*
G54D92*
X1030635Y824546D03*
G54D38*
X116731Y1052235D03*
X106619Y1056423D03*
X102431Y1066535D03*
X106619Y1076647D03*
X116731Y1080835D03*
Y1249086D03*
X106619Y1253274D03*
X102431Y1263386D03*
X106619Y1273498D03*
X116731Y1277686D03*
X126843Y1056423D03*
Y1076647D03*
X131031Y1066535D03*
X126843Y1253274D03*
X131031Y1263386D03*
X126843Y1273498D03*
X342840Y1056423D03*
X338652Y1066535D03*
X342840Y1076647D03*
Y1253274D03*
X338652Y1263386D03*
X342840Y1273498D03*
X352952Y1052235D03*
Y1080835D03*
Y1249086D03*
Y1277686D03*
X363064Y1056423D03*
Y1076647D03*
X367252Y1066535D03*
X363064Y1253274D03*
X367252Y1263386D03*
X363064Y1273498D03*
X563706Y1056423D03*
X559518Y1066535D03*
X563706Y1076647D03*
Y1253274D03*
X559518Y1263386D03*
X563706Y1273498D03*
X583930Y1056423D03*
X573818Y1052235D03*
X583930Y1076647D03*
X588118Y1066535D03*
X573818Y1080835D03*
X583930Y1253274D03*
X573818Y1249086D03*
X588118Y1263386D03*
X573818Y1277686D03*
X583930Y1273498D03*
X760433Y1480906D03*
X756274Y1490945D03*
X760433Y1500984D03*
X780511Y1480906D03*
X770472Y1476747D03*
Y1505143D03*
X780511Y1500984D03*
X799926Y1056423D03*
X795738Y1066535D03*
X799926Y1076647D03*
Y1253274D03*
X795738Y1263386D03*
X799926Y1273498D03*
X784670Y1490945D03*
X810040Y378544D03*
X805881Y388583D03*
X810040Y398622D03*
X810038Y1052235D03*
Y1080835D03*
Y1249086D03*
Y1277686D03*
X820079Y374385D03*
X830118Y378544D03*
X820079Y402781D03*
X830118Y398622D03*
X820150Y1056423D03*
Y1076647D03*
X824338Y1066535D03*
X820150Y1253274D03*
X824338Y1263386D03*
X820150Y1273498D03*
X834277Y388583D03*
X1010827Y378544D03*
X1006668Y388583D03*
X1010827Y398622D03*
X1020866Y374385D03*
Y402781D03*
X1020793Y1056423D03*
X1016605Y1066535D03*
X1020793Y1076647D03*
Y1253274D03*
X1016605Y1263386D03*
X1020793Y1273498D03*
X1030905Y378544D03*
X1035064Y388583D03*
X1030905Y398622D03*
X1041017Y1056423D03*
X1030905Y1052235D03*
X1041017Y1076647D03*
X1030905Y1080835D03*
X1041017Y1253274D03*
X1030905Y1249086D03*
Y1277686D03*
X1041017Y1273498D03*
X1045205Y1066535D03*
Y1263386D03*
X1060433Y1480906D03*
X1056274Y1490945D03*
X1060433Y1500984D03*
X1070472Y1476747D03*
Y1505143D03*
X1080511Y1480906D03*
X1084670Y1490945D03*
X1080511Y1500984D03*
X1252825Y1066535D03*
Y1263386D03*
X1267125Y1052235D03*
X1257013Y1056423D03*
Y1076647D03*
X1267125Y1080835D03*
Y1249086D03*
X1257013Y1253274D03*
Y1273498D03*
X1267125Y1277686D03*
X1277237Y1056423D03*
Y1076647D03*
X1281425Y1066535D03*
X1277237Y1253274D03*
X1281425Y1263386D03*
X1277237Y1273498D03*
X1477879Y1056423D03*
X1473691Y1066535D03*
X1477879Y1076647D03*
Y1253274D03*
X1473691Y1263386D03*
X1477879Y1273498D03*
X1498103Y1056423D03*
X1487991Y1052235D03*
X1498103Y1076647D03*
X1487991Y1080835D03*
X1498103Y1253274D03*
X1487991Y1249086D03*
Y1277686D03*
X1498103Y1273498D03*
X1502291Y1066535D03*
Y1263386D03*
X1709912Y1066535D03*
Y1263386D03*
X1724212Y1052235D03*
X1714100Y1056423D03*
Y1076647D03*
X1724212Y1080835D03*
Y1249086D03*
X1714100Y1253274D03*
Y1273498D03*
X1724212Y1277686D03*
X1734324Y1056423D03*
Y1076647D03*
X1738512Y1066535D03*
X1734324Y1253274D03*
X1738512Y1263386D03*
X1734324Y1273498D03*
G54D39*
X116731Y1066535D03*
Y1263386D03*
X352952Y1066535D03*
Y1263386D03*
X573818Y1066535D03*
Y1263386D03*
X810038Y1066535D03*
Y1263386D03*
X1030905Y1066535D03*
Y1263386D03*
X1267125Y1066535D03*
Y1263386D03*
X1487991Y1066535D03*
Y1263386D03*
X1724212Y1066535D03*
Y1263386D03*
G54D75*
X770472Y1490945D03*
X820079Y388583D03*
X1020866D03*
X1070472Y1490945D03*
G54D57*
X272635Y451628D03*
X729721D03*
X1186808D03*
X1643895D03*
G54D93*
X1131743Y779174D03*
X1139617Y775434D03*
Y782914D03*
G54D48*
X212460Y554847D03*
X669546D03*
X1126633D03*
X1583720D03*
G54D66*
X419061Y1143544D03*
Y1168740D03*
X446889Y1143544D03*
Y1168740D03*
X484648Y1143544D03*
Y1168740D03*
X512476Y1143544D03*
Y1168740D03*
X1333235Y1143544D03*
Y1168740D03*
X1361063Y1143544D03*
Y1168740D03*
X1398822Y1143544D03*
Y1168740D03*
X1426650Y1143544D03*
Y1168740D03*
G54D84*
X909360Y230906D03*
Y274606D03*
G54D49*
X212460Y551894D03*
Y557800D03*
X219546Y551894D03*
Y557800D03*
X669546Y551894D03*
Y557800D03*
X676632Y551894D03*
Y557800D03*
X1133719Y551894D03*
X1126633D03*
Y557800D03*
X1133719D03*
X1590806Y551894D03*
X1583720D03*
Y557800D03*
X1590806D03*
G54D58*
X372028Y1534029D03*
G54D76*
X798484Y980041D03*
Y1002089D03*
X801043Y980041D03*
X803602D03*
X806161D03*
X808720D03*
X811279D03*
X813839D03*
Y1002089D03*
X811279D03*
X808720D03*
X806161D03*
X803602D03*
X801043D03*
X816398Y980041D03*
X818957D03*
X821516D03*
X824075D03*
X826634D03*
Y1002089D03*
X824075D03*
X821516D03*
X818957D03*
X816398D03*
G54D94*
X1153433Y782873D03*
Y772243D03*
X1157173D03*
X1160913Y782873D03*
Y772243D03*
G54D67*
X414519Y1253318D03*
Y1261804D03*
X512430Y1253318D03*
Y1261804D03*
X1328693Y1253318D03*
Y1261804D03*
X1427004Y1253810D03*
Y1262296D03*
G54D85*
X904991Y843717D03*
Y846867D03*
X908140Y843717D03*
Y846867D03*
X901841Y843717D03*
Y846867D03*
Y872063D03*
Y875213D03*
X904991Y872063D03*
Y875213D03*
X908140Y872063D03*
Y875213D03*
X898692Y872063D03*
Y875213D03*
X941768Y864903D03*
Y868053D03*
X1331078Y834594D03*
Y837744D03*
X1334228Y850342D03*
Y853492D03*
X1337378Y859792D03*
Y862942D03*
Y853492D03*
Y856642D03*
X1349974Y866090D03*
Y869240D03*
X1346825Y866090D03*
Y869240D03*
X1340527Y866090D03*
Y869240D03*
X1343676Y866090D03*
Y869240D03*
X1340527Y872390D03*
Y875540D03*
X1343676Y872390D03*
Y875540D03*
X1346825Y872390D03*
Y875540D03*
X1349974Y872390D03*
Y875540D03*
X1362574Y837744D03*
Y840894D03*
Y853492D03*
Y856642D03*
X1356273Y866090D03*
Y869240D03*
X1359423Y866090D03*
Y869240D03*
Y872389D03*
Y875539D03*
X1356273Y872390D03*
Y875540D03*
X1353123Y866090D03*
Y869240D03*
Y872390D03*
Y875540D03*
G54D59*
X391691Y1321645D03*
X399171D03*
X897709Y545863D03*
X905189D03*
X1042180Y350954D03*
X1046180Y310454D03*
X1053660D03*
X1049660Y350954D03*
G54D77*
X849441Y1367717D03*
G54D95*
X1185312Y895751D03*
X1187871D03*
Y910317D03*
X1185312D03*
X1190431Y895751D03*
X1192990D03*
X1190431Y910317D03*
X1192990D03*
G54D68*
X414519Y1250868D03*
Y1264254D03*
X512430Y1250868D03*
Y1264254D03*
X1328693Y1250868D03*
Y1264254D03*
X1427004Y1251360D03*
Y1264746D03*
G54D86*
X911290Y846867D03*
Y853166D03*
Y859465D03*
Y865764D03*
Y868914D03*
X914440Y846867D03*
Y853166D03*
Y859465D03*
Y865764D03*
Y868914D03*
X1302770Y854824D03*
X1302776Y851193D03*
X1302883Y859088D03*
X1315311Y840921D03*
X1318461D03*
X1303195Y832247D03*
X1306345D03*
X1303183Y835985D03*
X1306333D03*
X1305920Y854824D03*
X1305926Y851193D03*
X1306033Y859088D03*
X1315330Y884988D03*
X1318480D03*
X1337377Y878689D03*
X1340527D03*
X1346826Y891288D03*
X1349976D03*
G54D87*
X901841Y856316D03*
Y853166D03*
X927438Y856316D03*
Y853166D03*
X923888Y856316D03*
Y853166D03*
X920739Y862615D03*
Y859465D03*
X930768Y856316D03*
Y853166D03*
X934268Y856316D03*
Y853166D03*
X1314560Y864182D03*
Y867332D03*
X1306387Y896580D03*
Y893430D03*
X1310482Y896580D03*
Y893430D03*
X1334228Y878690D03*
Y875540D03*
Y894438D03*
Y891288D03*
X1346827Y856642D03*
Y853492D03*
X1349977Y856642D03*
Y853492D03*
X1343678Y856642D03*
Y853492D03*
X1340528Y856642D03*
Y853492D03*
X1349977Y862942D03*
Y859792D03*
X1340528Y862942D03*
Y859792D03*
X1346826Y862942D03*
Y859792D03*
X1343677Y862942D03*
Y859792D03*
X1337377Y869241D03*
Y866091D03*
Y875540D03*
Y872390D03*
X1356275Y862942D03*
Y859792D03*
X1359425Y862942D03*
Y859792D03*
X1356275Y856642D03*
Y853492D03*
X1359425Y856642D03*
Y853492D03*
X1353126Y856642D03*
Y853492D03*
Y862942D03*
Y859792D03*
X1362572Y875539D03*
Y872389D03*
X1365724Y894438D03*
Y891288D03*
X1372023Y869241D03*
Y866091D03*
G54D69*
X490050Y804497D03*
Y800757D03*
Y808237D03*
X501074Y800757D03*
Y804497D03*
Y808237D03*
X1465833Y928108D03*
X1454809D03*
Y931848D03*
Y935588D03*
X1465833Y931848D03*
Y935588D03*
G54D96*
X1187951Y959596D03*
Y976722D03*
X1196219Y959596D03*
Y976722D03*
G54D78*
X843012Y1592787D03*
Y1602787D03*
Y1612787D03*
Y1622787D03*
X853012Y1592787D03*
Y1602787D03*
Y1612787D03*
Y1622787D03*
X878012Y1592787D03*
Y1602787D03*
Y1612787D03*
Y1622787D03*
X888012Y1592787D03*
Y1602787D03*
Y1612787D03*
Y1622787D03*
X913012Y1592787D03*
Y1602787D03*
Y1612787D03*
Y1622787D03*
X923012Y1592787D03*
Y1602787D03*
Y1612787D03*
Y1622787D03*
X948012Y1592787D03*
Y1602787D03*
Y1612787D03*
Y1622787D03*
X958012Y1592787D03*
Y1602787D03*
Y1612787D03*
Y1622787D03*
X983012Y1592787D03*
X993012D03*
X983012Y1602787D03*
Y1612787D03*
X993012Y1602787D03*
Y1612787D03*
X983012Y1622787D03*
X993012D03*
X1018012Y1592787D03*
X1028012D03*
X1018012Y1602787D03*
Y1612787D03*
X1028012Y1602787D03*
Y1612787D03*
X1018012Y1622787D03*
G54D97*
X1190805Y959596D03*
X1193365D03*
X1190805Y976722D03*
X1193365D03*
G54D88*
X953192Y-31798D03*
X978036Y-70978D03*
X1231336Y-80978D03*
X1236692Y-41928D03*
X1487836Y-80978D03*
X1523192Y-42058D03*
X1742336Y-80978D03*
X1807692Y-42188D03*
G54D79*
X876402Y797415D03*
X890326Y828548D03*
X895050D03*
X898835Y831912D03*
X893843Y832448D03*
X886120Y832295D03*
X955712Y833988D03*
X978978Y817618D03*
X984357Y777555D03*
X997051Y778833D03*
X990699Y778630D03*
X987990Y774005D03*
X987394Y787490D03*
X994051Y810871D03*
X996385Y816141D03*
X1007990Y765899D03*
X999990Y764566D03*
X1012695Y776728D03*
X999990Y774671D03*
X1011156Y809889D03*
X998376Y805985D03*
X1006054Y810969D03*
X1010699Y803454D03*
X1018015Y751565D03*
X1017664Y779101D03*
X1018071Y798490D03*
X1017955Y812097D03*
X1274396Y866896D03*
X1324470Y908192D03*
G54D98*
X1236871Y1715189D03*
Y1744208D03*
X1236864Y1773377D03*
X1235371Y1802909D03*
X1250055Y1710189D03*
Y1720189D03*
Y1739208D03*
Y1749208D03*
X1250048Y1768377D03*
Y1778377D03*
X1248555Y1797909D03*
Y1807909D03*
X1734069Y1710189D03*
Y1720189D03*
Y1739208D03*
Y1749208D03*
X1734062Y1768377D03*
Y1778377D03*
X1734069Y1797909D03*
Y1807909D03*
X1747253Y1715189D03*
Y1744208D03*
X1747246Y1773377D03*
X1747253Y1802909D03*
G54D89*
X970071Y1365652D03*
Y1409152D03*
G54D99*
X1269749Y937697D03*
X1276049Y935138D03*
Y940256D03*
M02*
